FILE_TYPE = MACRO_DRAWING;
SET COLOR_WIRE YELLOW;
SET COLOR_PROP ORANGE;
SET COLOR_DOT WHITE;
SET COLOR_ARC YELLOW;
SET COLOR_BODY GREEN;
SET COLOR_NOTE PURPLE;
SET PROP_DISPLAY VALUE;
SET PAGE_NUMBER P103;
FORCEADD OFFPAGE..5
(-8075 1950);
FORCEPROP 2 LAST $XR0 43 
J 0
(-8329 1950);
DISPLAY 0.638298 (-8329 1950);
PAINT MONO (-8329 1950);
FORCEPROP 2 LAST PATH I1
J 0
(-8325 2000);
DISPLAY 1.021277 (-8325 2000);
DISPLAY INVISIBLE (-8325 2000);
FORCEPROP 1 LAST COMMENT_BODY TRUE
J 0
(-7975 1875);
DISPLAY 0.872340 (-7975 1875);
PAINT GREEN (-7975 1875);
DISPLAY INVISIBLE (-7975 1875);
FORCEPROP 1 LAST OFFPAGE TRUE
J 0
(-7750 1825);
DISPLAY 0.872340 (-7750 1825);
PAINT GREEN (-7750 1825);
DISPLAY INVISIBLE (-7750 1825);
FORCEPROP 2 LAST CDS_LIB mstr_standard
J 0
(-8075 1950);
DISPLAY 0.808511 (-8075 1950);
DISPLAY INVISIBLE (-8075 1950);
FORCEADD OFFPAGE..6
(-8075 3550);
FORCEPROP 2 LAST $XR0 43 
J 0
(-8324 3550);
DISPLAY 0.638298 (-8324 3550);
PAINT MONO (-8324 3550);
FORCEPROP 2 LAST PATH I10
J 0
(-8350 3600);
DISPLAY 1.021277 (-8350 3600);
DISPLAY INVISIBLE (-8350 3600);
FORCEPROP 1 LAST COMMENT_BODY TRUE
J 0
(-7975 3475);
DISPLAY 0.872340 (-7975 3475);
PAINT GREEN (-7975 3475);
DISPLAY INVISIBLE (-7975 3475);
FORCEPROP 1 LAST OFFPAGE TRUE
J 0
(-7750 3425);
DISPLAY 0.872340 (-7750 3425);
PAINT GREEN (-7750 3425);
DISPLAY INVISIBLE (-7750 3425);
FORCEPROP 2 LAST CDS_LIB mstr_standard
J 0
(-8075 3550);
DISPLAY 0.723404 (-8075 3550);
PAINT MONO (-8075 3550);
DISPLAY INVISIBLE (-8075 3550);
FORCEADD TAP..1
(-5775 4100);
FORCEPROP 3 LASTPIN (-5825 4100) SIG_NAME M_G_CPU1_SA_DQ<6>
J 0
(-5815 4110);
DISPLAY 0.659574 (-5815 4110);
PAINT MONO (-5815 4110);
DISPLAY INVISIBLE (-5815 4110);
FORCEPROP 1 LASTPIN (-5825 4100) BN 6
J 0
(-5837 4108);
DISPLAY 0.489362 (-5837 4108);
PAINT GREEN (-5837 4108);
FORCEPROP 2 LAST CDS_LIB mstr_standard
J 0
(-5775 4100);
DISPLAY 0.723404 (-5775 4100);
PAINT MONO (-5775 4100);
DISPLAY INVISIBLE (-5775 4100);
FORCEPROP 1 LAST BODY_TYPE PLUMBING
J 0
(-5775 4150);
DISPLAY 0.872340 (-5775 4150);
PAINT GREEN (-5775 4150);
DISPLAY INVISIBLE (-5775 4150);
FORCEPROP 1 LAST HDL_TAP TRUE
J 0
(-5450 3975);
DISPLAY 0.872340 (-5450 3975);
DISPLAY INVISIBLE (-5450 3975);
FORCEPROP 1 LAST PATH I100
J 0
(-5777 4100);
DISPLAY 0.872340 (-5777 4100);
PAINT GREEN (-5777 4100);
DISPLAY INVISIBLE (-5777 4100);
FORCEADD TAP..1
(-5775 4250);
FORCEPROP 3 LASTPIN (-5825 4250) SIG_NAME M_G_CPU1_SA_DQ<9>
J 0
(-5815 4260);
DISPLAY 0.659574 (-5815 4260);
PAINT MONO (-5815 4260);
DISPLAY INVISIBLE (-5815 4260);
FORCEPROP 1 LASTPIN (-5825 4250) BN 9
J 0
(-5837 4258);
DISPLAY 0.489362 (-5837 4258);
PAINT GREEN (-5837 4258);
FORCEPROP 2 LAST CDS_LIB mstr_standard
J 0
(-5775 4250);
DISPLAY 0.723404 (-5775 4250);
PAINT MONO (-5775 4250);
DISPLAY INVISIBLE (-5775 4250);
FORCEPROP 1 LAST BODY_TYPE PLUMBING
J 0
(-5775 4300);
DISPLAY 0.872340 (-5775 4300);
PAINT GREEN (-5775 4300);
DISPLAY INVISIBLE (-5775 4300);
FORCEPROP 1 LAST HDL_TAP TRUE
J 0
(-5450 4125);
DISPLAY 0.872340 (-5450 4125);
DISPLAY INVISIBLE (-5450 4125);
FORCEPROP 1 LAST PATH I101
J 0
(-5777 4250);
DISPLAY 0.872340 (-5777 4250);
PAINT GREEN (-5777 4250);
DISPLAY INVISIBLE (-5777 4250);
FORCEADD TAP..1
(-5775 4200);
FORCEPROP 3 LASTPIN (-5825 4200) SIG_NAME M_G_CPU1_SA_DQ<8>
J 0
(-5815 4210);
DISPLAY 0.659574 (-5815 4210);
PAINT MONO (-5815 4210);
DISPLAY INVISIBLE (-5815 4210);
FORCEPROP 1 LASTPIN (-5825 4200) BN 8
J 0
(-5837 4208);
DISPLAY 0.489362 (-5837 4208);
PAINT GREEN (-5837 4208);
FORCEPROP 2 LAST CDS_LIB mstr_standard
J 0
(-5775 4200);
DISPLAY 0.723404 (-5775 4200);
PAINT MONO (-5775 4200);
DISPLAY INVISIBLE (-5775 4200);
FORCEPROP 1 LAST BODY_TYPE PLUMBING
J 0
(-5775 4250);
DISPLAY 0.872340 (-5775 4250);
PAINT GREEN (-5775 4250);
DISPLAY INVISIBLE (-5775 4250);
FORCEPROP 1 LAST HDL_TAP TRUE
J 0
(-5450 4075);
DISPLAY 0.872340 (-5450 4075);
DISPLAY INVISIBLE (-5450 4075);
FORCEPROP 1 LAST PATH I102
J 0
(-5777 4200);
DISPLAY 0.872340 (-5777 4200);
PAINT GREEN (-5777 4200);
DISPLAY INVISIBLE (-5777 4200);
FORCEADD TAP..1
(-5775 4050);
FORCEPROP 3 LASTPIN (-5825 4050) SIG_NAME M_G_CPU1_SA_DQ<5>
J 0
(-5815 4060);
DISPLAY 0.659574 (-5815 4060);
PAINT MONO (-5815 4060);
DISPLAY INVISIBLE (-5815 4060);
FORCEPROP 1 LASTPIN (-5825 4050) BN 5
J 0
(-5837 4058);
DISPLAY 0.489362 (-5837 4058);
PAINT GREEN (-5837 4058);
FORCEPROP 2 LAST CDS_LIB mstr_standard
J 0
(-5775 4050);
DISPLAY 0.723404 (-5775 4050);
PAINT MONO (-5775 4050);
DISPLAY INVISIBLE (-5775 4050);
FORCEPROP 1 LAST BODY_TYPE PLUMBING
J 0
(-5775 4100);
DISPLAY 0.872340 (-5775 4100);
PAINT GREEN (-5775 4100);
DISPLAY INVISIBLE (-5775 4100);
FORCEPROP 1 LAST HDL_TAP TRUE
J 0
(-5450 3925);
DISPLAY 0.872340 (-5450 3925);
DISPLAY INVISIBLE (-5450 3925);
FORCEPROP 1 LAST PATH I103
J 0
(-5777 4050);
DISPLAY 0.872340 (-5777 4050);
PAINT GREEN (-5777 4050);
DISPLAY INVISIBLE (-5777 4050);
FORCEADD TAP..1
(-5775 4450);
FORCEPROP 3 LASTPIN (-5825 4450) SIG_NAME M_G_CPU1_SA_DQ<13>
J 0
(-5815 4460);
DISPLAY 0.659574 (-5815 4460);
PAINT MONO (-5815 4460);
DISPLAY INVISIBLE (-5815 4460);
FORCEPROP 1 LASTPIN (-5825 4450) BN 13
J 0
(-5837 4458);
DISPLAY 0.489362 (-5837 4458);
PAINT GREEN (-5837 4458);
FORCEPROP 2 LAST CDS_LIB mstr_standard
J 0
(-5775 4450);
DISPLAY 0.723404 (-5775 4450);
PAINT MONO (-5775 4450);
DISPLAY INVISIBLE (-5775 4450);
FORCEPROP 1 LAST BODY_TYPE PLUMBING
J 0
(-5775 4500);
DISPLAY 0.872340 (-5775 4500);
PAINT GREEN (-5775 4500);
DISPLAY INVISIBLE (-5775 4500);
FORCEPROP 1 LAST HDL_TAP TRUE
J 0
(-5450 4325);
DISPLAY 0.872340 (-5450 4325);
DISPLAY INVISIBLE (-5450 4325);
FORCEPROP 1 LAST PATH I104
J 0
(-5777 4450);
DISPLAY 0.872340 (-5777 4450);
PAINT GREEN (-5777 4450);
DISPLAY INVISIBLE (-5777 4450);
FORCEADD TAP..1
(-5775 4500);
FORCEPROP 3 LASTPIN (-5825 4500) SIG_NAME M_G_CPU1_SA_DQ<14>
J 0
(-5815 4510);
DISPLAY 0.659574 (-5815 4510);
PAINT MONO (-5815 4510);
DISPLAY INVISIBLE (-5815 4510);
FORCEPROP 1 LASTPIN (-5825 4500) BN 14
J 0
(-5837 4508);
DISPLAY 0.489362 (-5837 4508);
PAINT GREEN (-5837 4508);
FORCEPROP 2 LAST CDS_LIB mstr_standard
J 0
(-5775 4500);
DISPLAY 0.723404 (-5775 4500);
PAINT MONO (-5775 4500);
DISPLAY INVISIBLE (-5775 4500);
FORCEPROP 1 LAST BODY_TYPE PLUMBING
J 0
(-5775 4550);
DISPLAY 0.872340 (-5775 4550);
PAINT GREEN (-5775 4550);
DISPLAY INVISIBLE (-5775 4550);
FORCEPROP 1 LAST HDL_TAP TRUE
J 0
(-5450 4375);
DISPLAY 0.872340 (-5450 4375);
DISPLAY INVISIBLE (-5450 4375);
FORCEPROP 1 LAST PATH I105
J 0
(-5777 4500);
DISPLAY 0.872340 (-5777 4500);
PAINT GREEN (-5777 4500);
DISPLAY INVISIBLE (-5777 4500);
FORCEADD TAP..1
(-5775 4300);
FORCEPROP 3 LASTPIN (-5825 4300) SIG_NAME M_G_CPU1_SA_DQ<10>
J 0
(-5815 4310);
DISPLAY 0.659574 (-5815 4310);
PAINT MONO (-5815 4310);
DISPLAY INVISIBLE (-5815 4310);
FORCEPROP 1 LASTPIN (-5825 4300) BN 10
J 0
(-5837 4308);
DISPLAY 0.489362 (-5837 4308);
PAINT GREEN (-5837 4308);
FORCEPROP 2 LAST CDS_LIB mstr_standard
J 0
(-5775 4300);
DISPLAY 0.723404 (-5775 4300);
PAINT MONO (-5775 4300);
DISPLAY INVISIBLE (-5775 4300);
FORCEPROP 1 LAST BODY_TYPE PLUMBING
J 0
(-5775 4350);
DISPLAY 0.872340 (-5775 4350);
PAINT GREEN (-5775 4350);
DISPLAY INVISIBLE (-5775 4350);
FORCEPROP 1 LAST HDL_TAP TRUE
J 0
(-5450 4175);
DISPLAY 0.872340 (-5450 4175);
DISPLAY INVISIBLE (-5450 4175);
FORCEPROP 1 LAST PATH I106
J 0
(-5777 4300);
DISPLAY 0.872340 (-5777 4300);
PAINT GREEN (-5777 4300);
DISPLAY INVISIBLE (-5777 4300);
FORCEADD TAP..1
(-5775 4350);
FORCEPROP 3 LASTPIN (-5825 4350) SIG_NAME M_G_CPU1_SA_DQ<11>
J 0
(-5815 4360);
DISPLAY 0.659574 (-5815 4360);
PAINT MONO (-5815 4360);
DISPLAY INVISIBLE (-5815 4360);
FORCEPROP 1 LASTPIN (-5825 4350) BN 11
J 0
(-5837 4358);
DISPLAY 0.489362 (-5837 4358);
PAINT GREEN (-5837 4358);
FORCEPROP 2 LAST CDS_LIB mstr_standard
J 0
(-5775 4350);
DISPLAY 0.723404 (-5775 4350);
PAINT MONO (-5775 4350);
DISPLAY INVISIBLE (-5775 4350);
FORCEPROP 1 LAST BODY_TYPE PLUMBING
J 0
(-5775 4400);
DISPLAY 0.872340 (-5775 4400);
PAINT GREEN (-5775 4400);
DISPLAY INVISIBLE (-5775 4400);
FORCEPROP 1 LAST HDL_TAP TRUE
J 0
(-5450 4225);
DISPLAY 0.872340 (-5450 4225);
DISPLAY INVISIBLE (-5450 4225);
FORCEPROP 1 LAST PATH I107
J 0
(-5777 4350);
DISPLAY 0.872340 (-5777 4350);
PAINT GREEN (-5777 4350);
DISPLAY INVISIBLE (-5777 4350);
FORCEADD TAP..1
(-5775 4400);
FORCEPROP 3 LASTPIN (-5825 4400) SIG_NAME M_G_CPU1_SA_DQ<12>
J 0
(-5815 4410);
DISPLAY 0.659574 (-5815 4410);
PAINT MONO (-5815 4410);
DISPLAY INVISIBLE (-5815 4410);
FORCEPROP 1 LASTPIN (-5825 4400) BN 12
J 0
(-5837 4408);
DISPLAY 0.489362 (-5837 4408);
PAINT GREEN (-5837 4408);
FORCEPROP 2 LAST CDS_LIB mstr_standard
J 0
(-5775 4400);
DISPLAY 0.723404 (-5775 4400);
PAINT MONO (-5775 4400);
DISPLAY INVISIBLE (-5775 4400);
FORCEPROP 1 LAST BODY_TYPE PLUMBING
J 0
(-5775 4450);
DISPLAY 0.872340 (-5775 4450);
PAINT GREEN (-5775 4450);
DISPLAY INVISIBLE (-5775 4450);
FORCEPROP 1 LAST HDL_TAP TRUE
J 0
(-5450 4275);
DISPLAY 0.872340 (-5450 4275);
DISPLAY INVISIBLE (-5450 4275);
FORCEPROP 1 LAST PATH I108
J 0
(-5777 4400);
DISPLAY 0.872340 (-5777 4400);
PAINT GREEN (-5777 4400);
DISPLAY INVISIBLE (-5777 4400);
FORCEADD TAP..1
(-5775 4700);
FORCEPROP 3 LASTPIN (-5825 4700) SIG_NAME M_G_CPU1_SA_DQ<18>
J 0
(-5815 4710);
DISPLAY 0.659574 (-5815 4710);
PAINT MONO (-5815 4710);
DISPLAY INVISIBLE (-5815 4710);
FORCEPROP 1 LASTPIN (-5825 4700) BN 18
J 0
(-5837 4708);
DISPLAY 0.489362 (-5837 4708);
PAINT GREEN (-5837 4708);
FORCEPROP 2 LAST CDS_LIB mstr_standard
J 0
(-5775 4700);
DISPLAY 0.723404 (-5775 4700);
PAINT MONO (-5775 4700);
DISPLAY INVISIBLE (-5775 4700);
FORCEPROP 1 LAST BODY_TYPE PLUMBING
J 0
(-5775 4750);
DISPLAY 0.872340 (-5775 4750);
PAINT GREEN (-5775 4750);
DISPLAY INVISIBLE (-5775 4750);
FORCEPROP 1 LAST HDL_TAP TRUE
J 0
(-5450 4575);
DISPLAY 0.872340 (-5450 4575);
DISPLAY INVISIBLE (-5450 4575);
FORCEPROP 1 LAST PATH I109
J 0
(-5777 4700);
DISPLAY 0.872340 (-5777 4700);
PAINT GREEN (-5777 4700);
DISPLAY INVISIBLE (-5777 4700);
FORCEADD OFFPAGE..6
(-8075 4000);
FORCEPROP 2 LAST $XR0 43 
J 0
(-8324 4000);
DISPLAY 0.638298 (-8324 4000);
PAINT MONO (-8324 4000);
FORCEPROP 2 LAST PATH I11
J 0
(-8350 4050);
DISPLAY 1.021277 (-8350 4050);
DISPLAY INVISIBLE (-8350 4050);
FORCEPROP 1 LAST COMMENT_BODY TRUE
J 0
(-7975 3925);
DISPLAY 0.872340 (-7975 3925);
PAINT GREEN (-7975 3925);
DISPLAY INVISIBLE (-7975 3925);
FORCEPROP 1 LAST OFFPAGE TRUE
J 0
(-7750 3875);
DISPLAY 0.872340 (-7750 3875);
PAINT GREEN (-7750 3875);
DISPLAY INVISIBLE (-7750 3875);
FORCEPROP 2 LAST CDS_LIB mstr_standard
J 0
(-8075 4000);
DISPLAY 0.723404 (-8075 4000);
PAINT MONO (-8075 4000);
DISPLAY INVISIBLE (-8075 4000);
FORCEADD TAP..1
(-5775 4750);
FORCEPROP 3 LASTPIN (-5825 4750) SIG_NAME M_G_CPU1_SA_DQ<19>
J 0
(-5815 4760);
DISPLAY 0.659574 (-5815 4760);
PAINT MONO (-5815 4760);
DISPLAY INVISIBLE (-5815 4760);
FORCEPROP 1 LASTPIN (-5825 4750) BN 19
J 0
(-5837 4758);
DISPLAY 0.489362 (-5837 4758);
PAINT GREEN (-5837 4758);
FORCEPROP 2 LAST CDS_LIB mstr_standard
J 0
(-5775 4750);
DISPLAY 0.723404 (-5775 4750);
PAINT MONO (-5775 4750);
DISPLAY INVISIBLE (-5775 4750);
FORCEPROP 1 LAST BODY_TYPE PLUMBING
J 0
(-5775 4800);
DISPLAY 0.872340 (-5775 4800);
PAINT GREEN (-5775 4800);
DISPLAY INVISIBLE (-5775 4800);
FORCEPROP 1 LAST HDL_TAP TRUE
J 0
(-5450 4625);
DISPLAY 0.872340 (-5450 4625);
DISPLAY INVISIBLE (-5450 4625);
FORCEPROP 1 LAST PATH I110
J 0
(-5777 4750);
DISPLAY 0.872340 (-5777 4750);
PAINT GREEN (-5777 4750);
DISPLAY INVISIBLE (-5777 4750);
FORCEADD TAP..1
(-5775 4550);
FORCEPROP 3 LASTPIN (-5825 4550) SIG_NAME M_G_CPU1_SA_DQ<15>
J 0
(-5815 4560);
DISPLAY 0.659574 (-5815 4560);
PAINT MONO (-5815 4560);
DISPLAY INVISIBLE (-5815 4560);
FORCEPROP 1 LASTPIN (-5825 4550) BN 15
J 0
(-5837 4558);
DISPLAY 0.489362 (-5837 4558);
PAINT GREEN (-5837 4558);
FORCEPROP 2 LAST CDS_LIB mstr_standard
J 0
(-5775 4550);
DISPLAY 0.723404 (-5775 4550);
PAINT MONO (-5775 4550);
DISPLAY INVISIBLE (-5775 4550);
FORCEPROP 1 LAST BODY_TYPE PLUMBING
J 0
(-5775 4600);
DISPLAY 0.872340 (-5775 4600);
PAINT GREEN (-5775 4600);
DISPLAY INVISIBLE (-5775 4600);
FORCEPROP 1 LAST HDL_TAP TRUE
J 0
(-5450 4425);
DISPLAY 0.872340 (-5450 4425);
DISPLAY INVISIBLE (-5450 4425);
FORCEPROP 1 LAST PATH I111
J 0
(-5777 4550);
DISPLAY 0.872340 (-5777 4550);
PAINT GREEN (-5777 4550);
DISPLAY INVISIBLE (-5777 4550);
FORCEADD TAP..1
(-5775 4600);
FORCEPROP 3 LASTPIN (-5825 4600) SIG_NAME M_G_CPU1_SA_DQ<16>
J 0
(-5815 4610);
DISPLAY 0.659574 (-5815 4610);
PAINT MONO (-5815 4610);
DISPLAY INVISIBLE (-5815 4610);
FORCEPROP 1 LASTPIN (-5825 4600) BN 16
J 0
(-5837 4608);
DISPLAY 0.489362 (-5837 4608);
PAINT GREEN (-5837 4608);
FORCEPROP 2 LAST CDS_LIB mstr_standard
J 0
(-5775 4600);
DISPLAY 0.723404 (-5775 4600);
PAINT MONO (-5775 4600);
DISPLAY INVISIBLE (-5775 4600);
FORCEPROP 1 LAST BODY_TYPE PLUMBING
J 0
(-5775 4650);
DISPLAY 0.872340 (-5775 4650);
PAINT GREEN (-5775 4650);
DISPLAY INVISIBLE (-5775 4650);
FORCEPROP 1 LAST HDL_TAP TRUE
J 0
(-5450 4475);
DISPLAY 0.872340 (-5450 4475);
DISPLAY INVISIBLE (-5450 4475);
FORCEPROP 1 LAST PATH I112
J 0
(-5777 4600);
DISPLAY 0.872340 (-5777 4600);
PAINT GREEN (-5777 4600);
DISPLAY INVISIBLE (-5777 4600);
FORCEADD TAP..1
(-5775 4650);
FORCEPROP 3 LASTPIN (-5825 4650) SIG_NAME M_G_CPU1_SA_DQ<17>
J 0
(-5815 4660);
DISPLAY 0.659574 (-5815 4660);
PAINT MONO (-5815 4660);
DISPLAY INVISIBLE (-5815 4660);
FORCEPROP 1 LASTPIN (-5825 4650) BN 17
J 0
(-5837 4658);
DISPLAY 0.489362 (-5837 4658);
PAINT GREEN (-5837 4658);
FORCEPROP 2 LAST CDS_LIB mstr_standard
J 0
(-5775 4650);
DISPLAY 0.723404 (-5775 4650);
PAINT MONO (-5775 4650);
DISPLAY INVISIBLE (-5775 4650);
FORCEPROP 1 LAST BODY_TYPE PLUMBING
J 0
(-5775 4700);
DISPLAY 0.872340 (-5775 4700);
PAINT GREEN (-5775 4700);
DISPLAY INVISIBLE (-5775 4700);
FORCEPROP 1 LAST HDL_TAP TRUE
J 0
(-5450 4525);
DISPLAY 0.872340 (-5450 4525);
DISPLAY INVISIBLE (-5450 4525);
FORCEPROP 1 LAST PATH I113
J 0
(-5777 4650);
DISPLAY 0.872340 (-5777 4650);
PAINT GREEN (-5777 4650);
DISPLAY INVISIBLE (-5777 4650);
FORCEADD TAP..1
(-5775 5000);
FORCEPROP 3 LASTPIN (-5825 5000) SIG_NAME M_G_CPU1_SA_DQ<24>
J 0
(-5815 5010);
DISPLAY 0.659574 (-5815 5010);
PAINT MONO (-5815 5010);
DISPLAY INVISIBLE (-5815 5010);
FORCEPROP 1 LASTPIN (-5825 5000) BN 24
J 0
(-5837 5008);
DISPLAY 0.489362 (-5837 5008);
PAINT GREEN (-5837 5008);
FORCEPROP 2 LAST CDS_LIB mstr_standard
J 0
(-5775 5000);
DISPLAY 0.723404 (-5775 5000);
PAINT MONO (-5775 5000);
DISPLAY INVISIBLE (-5775 5000);
FORCEPROP 1 LAST BODY_TYPE PLUMBING
J 0
(-5775 5050);
DISPLAY 0.872340 (-5775 5050);
PAINT GREEN (-5775 5050);
DISPLAY INVISIBLE (-5775 5050);
FORCEPROP 1 LAST HDL_TAP TRUE
J 0
(-5450 4875);
DISPLAY 0.872340 (-5450 4875);
DISPLAY INVISIBLE (-5450 4875);
FORCEPROP 1 LAST PATH I114
J 0
(-5777 5000);
DISPLAY 0.872340 (-5777 5000);
PAINT GREEN (-5777 5000);
DISPLAY INVISIBLE (-5777 5000);
FORCEADD TAP..1
(-5775 4950);
FORCEPROP 3 LASTPIN (-5825 4950) SIG_NAME M_G_CPU1_SA_DQ<23>
J 0
(-5815 4960);
DISPLAY 0.659574 (-5815 4960);
PAINT MONO (-5815 4960);
DISPLAY INVISIBLE (-5815 4960);
FORCEPROP 1 LASTPIN (-5825 4950) BN 23
J 0
(-5837 4958);
DISPLAY 0.489362 (-5837 4958);
PAINT GREEN (-5837 4958);
FORCEPROP 2 LAST CDS_LIB mstr_standard
J 0
(-5775 4950);
DISPLAY 0.723404 (-5775 4950);
PAINT MONO (-5775 4950);
DISPLAY INVISIBLE (-5775 4950);
FORCEPROP 1 LAST BODY_TYPE PLUMBING
J 0
(-5775 5000);
DISPLAY 0.872340 (-5775 5000);
PAINT GREEN (-5775 5000);
DISPLAY INVISIBLE (-5775 5000);
FORCEPROP 1 LAST HDL_TAP TRUE
J 0
(-5450 4825);
DISPLAY 0.872340 (-5450 4825);
DISPLAY INVISIBLE (-5450 4825);
FORCEPROP 1 LAST PATH I115
J 0
(-5777 4950);
DISPLAY 0.872340 (-5777 4950);
PAINT GREEN (-5777 4950);
DISPLAY INVISIBLE (-5777 4950);
FORCEADD TAP..1
(-5775 5050);
FORCEPROP 3 LASTPIN (-5825 5050) SIG_NAME M_G_CPU1_SA_DQ<25>
J 0
(-5815 5060);
DISPLAY 0.659574 (-5815 5060);
PAINT MONO (-5815 5060);
DISPLAY INVISIBLE (-5815 5060);
FORCEPROP 1 LASTPIN (-5825 5050) BN 25
J 0
(-5837 5058);
DISPLAY 0.489362 (-5837 5058);
PAINT GREEN (-5837 5058);
FORCEPROP 2 LAST CDS_LIB mstr_standard
J 0
(-5775 5050);
DISPLAY 0.723404 (-5775 5050);
PAINT MONO (-5775 5050);
DISPLAY INVISIBLE (-5775 5050);
FORCEPROP 1 LAST BODY_TYPE PLUMBING
J 0
(-5775 5100);
DISPLAY 0.872340 (-5775 5100);
PAINT GREEN (-5775 5100);
DISPLAY INVISIBLE (-5775 5100);
FORCEPROP 1 LAST HDL_TAP TRUE
J 0
(-5450 4925);
DISPLAY 0.872340 (-5450 4925);
DISPLAY INVISIBLE (-5450 4925);
FORCEPROP 1 LAST PATH I116
J 0
(-5777 5050);
DISPLAY 0.872340 (-5777 5050);
PAINT GREEN (-5777 5050);
DISPLAY INVISIBLE (-5777 5050);
FORCEADD TAP..1
(-5775 4800);
FORCEPROP 3 LASTPIN (-5825 4800) SIG_NAME M_G_CPU1_SA_DQ<20>
J 0
(-5815 4810);
DISPLAY 0.659574 (-5815 4810);
PAINT MONO (-5815 4810);
DISPLAY INVISIBLE (-5815 4810);
FORCEPROP 1 LASTPIN (-5825 4800) BN 20
J 0
(-5837 4808);
DISPLAY 0.489362 (-5837 4808);
PAINT GREEN (-5837 4808);
FORCEPROP 2 LAST CDS_LIB mstr_standard
J 0
(-5775 4800);
DISPLAY 0.723404 (-5775 4800);
PAINT MONO (-5775 4800);
DISPLAY INVISIBLE (-5775 4800);
FORCEPROP 1 LAST BODY_TYPE PLUMBING
J 0
(-5775 4850);
DISPLAY 0.872340 (-5775 4850);
PAINT GREEN (-5775 4850);
DISPLAY INVISIBLE (-5775 4850);
FORCEPROP 1 LAST HDL_TAP TRUE
J 0
(-5450 4675);
DISPLAY 0.872340 (-5450 4675);
DISPLAY INVISIBLE (-5450 4675);
FORCEPROP 1 LAST PATH I117
J 0
(-5777 4800);
DISPLAY 0.872340 (-5777 4800);
PAINT GREEN (-5777 4800);
DISPLAY INVISIBLE (-5777 4800);
FORCEADD TAP..1
(-5775 4850);
FORCEPROP 3 LASTPIN (-5825 4850) SIG_NAME M_G_CPU1_SA_DQ<21>
J 0
(-5815 4860);
DISPLAY 0.659574 (-5815 4860);
PAINT MONO (-5815 4860);
DISPLAY INVISIBLE (-5815 4860);
FORCEPROP 1 LASTPIN (-5825 4850) BN 21
J 0
(-5837 4858);
DISPLAY 0.489362 (-5837 4858);
PAINT GREEN (-5837 4858);
FORCEPROP 2 LAST CDS_LIB mstr_standard
J 0
(-5775 4850);
DISPLAY 0.723404 (-5775 4850);
PAINT MONO (-5775 4850);
DISPLAY INVISIBLE (-5775 4850);
FORCEPROP 1 LAST BODY_TYPE PLUMBING
J 0
(-5775 4900);
DISPLAY 0.872340 (-5775 4900);
PAINT GREEN (-5775 4900);
DISPLAY INVISIBLE (-5775 4900);
FORCEPROP 1 LAST HDL_TAP TRUE
J 0
(-5450 4725);
DISPLAY 0.872340 (-5450 4725);
DISPLAY INVISIBLE (-5450 4725);
FORCEPROP 1 LAST PATH I118
J 0
(-5777 4850);
DISPLAY 0.872340 (-5777 4850);
PAINT GREEN (-5777 4850);
DISPLAY INVISIBLE (-5777 4850);
FORCEADD TAP..1
(-5775 4900);
FORCEPROP 3 LASTPIN (-5825 4900) SIG_NAME M_G_CPU1_SA_DQ<22>
J 0
(-5815 4910);
DISPLAY 0.659574 (-5815 4910);
PAINT MONO (-5815 4910);
DISPLAY INVISIBLE (-5815 4910);
FORCEPROP 1 LASTPIN (-5825 4900) BN 22
J 0
(-5837 4908);
DISPLAY 0.489362 (-5837 4908);
PAINT GREEN (-5837 4908);
FORCEPROP 2 LAST CDS_LIB mstr_standard
J 0
(-5775 4900);
DISPLAY 0.723404 (-5775 4900);
PAINT MONO (-5775 4900);
DISPLAY INVISIBLE (-5775 4900);
FORCEPROP 1 LAST BODY_TYPE PLUMBING
J 0
(-5775 4950);
DISPLAY 0.872340 (-5775 4950);
PAINT GREEN (-5775 4950);
DISPLAY INVISIBLE (-5775 4950);
FORCEPROP 1 LAST HDL_TAP TRUE
J 0
(-5450 4775);
DISPLAY 0.872340 (-5450 4775);
DISPLAY INVISIBLE (-5450 4775);
FORCEPROP 1 LAST PATH I119
J 0
(-5777 4900);
DISPLAY 0.872340 (-5777 4900);
PAINT GREEN (-5777 4900);
DISPLAY INVISIBLE (-5777 4900);
FORCEADD OFFPAGE..1
(-8075 4050);
FORCEPROP 2 LAST $XR0 43 
J 0
(-8296 4050);
DISPLAY 0.638298 (-8296 4050);
PAINT MONO (-8296 4050);
FORCEPROP 2 LAST PATH I12
J 0
(-8325 4100);
DISPLAY 1.021277 (-8325 4100);
DISPLAY INVISIBLE (-8325 4100);
FORCEPROP 1 LAST COMMENT_BODY TRUE
J 0
(-7950 3950);
DISPLAY 0.872340 (-7950 3950);
PAINT GREEN (-7950 3950);
DISPLAY INVISIBLE (-7950 3950);
FORCEPROP 1 LAST OFFPAGE TRUE
J 0
(-7750 3925);
DISPLAY 0.872340 (-7750 3925);
PAINT GREEN (-7750 3925);
DISPLAY INVISIBLE (-7750 3925);
FORCEPROP 2 LAST CDS_LIB mstr_standard
J 0
(-8075 4050);
DISPLAY 0.808511 (-8075 4050);
DISPLAY INVISIBLE (-8075 4050);
FORCEADD TAP..1
(-5775 5300);
FORCEPROP 3 LASTPIN (-5825 5300) SIG_NAME M_G_CPU1_SA_DQ<30>
J 0
(-5815 5310);
DISPLAY 0.659574 (-5815 5310);
PAINT MONO (-5815 5310);
DISPLAY INVISIBLE (-5815 5310);
FORCEPROP 1 LASTPIN (-5825 5300) BN 30
J 0
(-5837 5308);
DISPLAY 0.489362 (-5837 5308);
PAINT GREEN (-5837 5308);
FORCEPROP 2 LAST CDS_LIB mstr_standard
J 0
(-5775 5300);
DISPLAY 0.723404 (-5775 5300);
PAINT MONO (-5775 5300);
DISPLAY INVISIBLE (-5775 5300);
FORCEPROP 1 LAST BODY_TYPE PLUMBING
J 0
(-5775 5350);
DISPLAY 0.872340 (-5775 5350);
PAINT GREEN (-5775 5350);
DISPLAY INVISIBLE (-5775 5350);
FORCEPROP 1 LAST HDL_TAP TRUE
J 0
(-5450 5175);
DISPLAY 0.872340 (-5450 5175);
DISPLAY INVISIBLE (-5450 5175);
FORCEPROP 1 LAST PATH I120
J 0
(-5777 5300);
DISPLAY 0.872340 (-5777 5300);
PAINT GREEN (-5777 5300);
DISPLAY INVISIBLE (-5777 5300);
FORCEADD TAP..1
(-5775 5200);
FORCEPROP 3 LASTPIN (-5825 5200) SIG_NAME M_G_CPU1_SA_DQ<28>
J 0
(-5815 5210);
DISPLAY 0.659574 (-5815 5210);
PAINT MONO (-5815 5210);
DISPLAY INVISIBLE (-5815 5210);
FORCEPROP 1 LASTPIN (-5825 5200) BN 28
J 0
(-5837 5208);
DISPLAY 0.489362 (-5837 5208);
PAINT GREEN (-5837 5208);
FORCEPROP 2 LAST CDS_LIB mstr_standard
J 0
(-5775 5200);
DISPLAY 0.723404 (-5775 5200);
PAINT MONO (-5775 5200);
DISPLAY INVISIBLE (-5775 5200);
FORCEPROP 1 LAST BODY_TYPE PLUMBING
J 0
(-5775 5250);
DISPLAY 0.872340 (-5775 5250);
PAINT GREEN (-5775 5250);
DISPLAY INVISIBLE (-5775 5250);
FORCEPROP 1 LAST HDL_TAP TRUE
J 0
(-5450 5075);
DISPLAY 0.872340 (-5450 5075);
DISPLAY INVISIBLE (-5450 5075);
FORCEPROP 1 LAST PATH I121
J 0
(-5777 5200);
DISPLAY 0.872340 (-5777 5200);
PAINT GREEN (-5777 5200);
DISPLAY INVISIBLE (-5777 5200);
FORCEADD TAP..1
(-5775 5250);
FORCEPROP 3 LASTPIN (-5825 5250) SIG_NAME M_G_CPU1_SA_DQ<29>
J 0
(-5815 5260);
DISPLAY 0.659574 (-5815 5260);
PAINT MONO (-5815 5260);
DISPLAY INVISIBLE (-5815 5260);
FORCEPROP 1 LASTPIN (-5825 5250) BN 29
J 0
(-5837 5258);
DISPLAY 0.489362 (-5837 5258);
PAINT GREEN (-5837 5258);
FORCEPROP 2 LAST CDS_LIB mstr_standard
J 0
(-5775 5250);
DISPLAY 0.723404 (-5775 5250);
PAINT MONO (-5775 5250);
DISPLAY INVISIBLE (-5775 5250);
FORCEPROP 1 LAST BODY_TYPE PLUMBING
J 0
(-5775 5300);
DISPLAY 0.872340 (-5775 5300);
PAINT GREEN (-5775 5300);
DISPLAY INVISIBLE (-5775 5300);
FORCEPROP 1 LAST HDL_TAP TRUE
J 0
(-5450 5125);
DISPLAY 0.872340 (-5450 5125);
DISPLAY INVISIBLE (-5450 5125);
FORCEPROP 1 LAST PATH I122
J 0
(-5777 5250);
DISPLAY 0.872340 (-5777 5250);
PAINT GREEN (-5777 5250);
DISPLAY INVISIBLE (-5777 5250);
FORCEADD TAP..1
(-5775 5150);
FORCEPROP 3 LASTPIN (-5825 5150) SIG_NAME M_G_CPU1_SA_DQ<27>
J 0
(-5815 5160);
DISPLAY 0.659574 (-5815 5160);
PAINT MONO (-5815 5160);
DISPLAY INVISIBLE (-5815 5160);
FORCEPROP 1 LASTPIN (-5825 5150) BN 27
J 0
(-5837 5158);
DISPLAY 0.489362 (-5837 5158);
PAINT GREEN (-5837 5158);
FORCEPROP 2 LAST CDS_LIB mstr_standard
J 0
(-5775 5150);
DISPLAY 0.723404 (-5775 5150);
PAINT MONO (-5775 5150);
DISPLAY INVISIBLE (-5775 5150);
FORCEPROP 1 LAST BODY_TYPE PLUMBING
J 0
(-5775 5200);
DISPLAY 0.872340 (-5775 5200);
PAINT GREEN (-5775 5200);
DISPLAY INVISIBLE (-5775 5200);
FORCEPROP 1 LAST HDL_TAP TRUE
J 0
(-5450 5025);
DISPLAY 0.872340 (-5450 5025);
DISPLAY INVISIBLE (-5450 5025);
FORCEPROP 1 LAST PATH I123
J 0
(-5777 5150);
DISPLAY 0.872340 (-5777 5150);
PAINT GREEN (-5777 5150);
DISPLAY INVISIBLE (-5777 5150);
FORCEADD TAP..1
(-5775 5100);
FORCEPROP 3 LASTPIN (-5825 5100) SIG_NAME M_G_CPU1_SA_DQ<26>
J 0
(-5815 5110);
DISPLAY 0.659574 (-5815 5110);
PAINT MONO (-5815 5110);
DISPLAY INVISIBLE (-5815 5110);
FORCEPROP 1 LASTPIN (-5825 5100) BN 26
J 0
(-5837 5108);
DISPLAY 0.489362 (-5837 5108);
PAINT GREEN (-5837 5108);
FORCEPROP 2 LAST CDS_LIB mstr_standard
J 0
(-5775 5100);
DISPLAY 0.723404 (-5775 5100);
PAINT MONO (-5775 5100);
DISPLAY INVISIBLE (-5775 5100);
FORCEPROP 1 LAST BODY_TYPE PLUMBING
J 0
(-5775 5150);
DISPLAY 0.872340 (-5775 5150);
PAINT GREEN (-5775 5150);
DISPLAY INVISIBLE (-5775 5150);
FORCEPROP 1 LAST HDL_TAP TRUE
J 0
(-5450 4975);
DISPLAY 0.872340 (-5450 4975);
DISPLAY INVISIBLE (-5450 4975);
FORCEPROP 1 LAST PATH I124
J 0
(-5777 5100);
DISPLAY 0.872340 (-5777 5100);
PAINT GREEN (-5777 5100);
DISPLAY INVISIBLE (-5777 5100);
FORCEADD TAP..1
(-5775 5350);
FORCEPROP 3 LASTPIN (-5825 5350) SIG_NAME M_G_CPU1_SA_DQ<31>
J 0
(-5815 5360);
DISPLAY 0.659574 (-5815 5360);
PAINT MONO (-5815 5360);
DISPLAY INVISIBLE (-5815 5360);
FORCEPROP 1 LASTPIN (-5825 5350) BN 31
J 0
(-5837 5358);
DISPLAY 0.489362 (-5837 5358);
PAINT GREEN (-5837 5358);
FORCEPROP 2 LAST CDS_LIB mstr_standard
J 0
(-5775 5350);
DISPLAY 0.723404 (-5775 5350);
PAINT MONO (-5775 5350);
DISPLAY INVISIBLE (-5775 5350);
FORCEPROP 1 LAST BODY_TYPE PLUMBING
J 0
(-5775 5400);
DISPLAY 0.872340 (-5775 5400);
PAINT GREEN (-5775 5400);
DISPLAY INVISIBLE (-5775 5400);
FORCEPROP 1 LAST HDL_TAP TRUE
J 0
(-5450 5225);
DISPLAY 0.872340 (-5450 5225);
DISPLAY INVISIBLE (-5450 5225);
FORCEPROP 1 LAST PATH I125
J 0
(-5777 5350);
DISPLAY 0.872340 (-5777 5350);
PAINT GREEN (-5777 5350);
DISPLAY INVISIBLE (-5777 5350);
FORCEADD OFFPAGE..3
(-5175 5400);
FORCEPROP 2 LAST $XR0 43 
J 0
(-4961 5400);
DISPLAY 0.638298 (-4961 5400);
PAINT MONO (-4961 5400);
FORCEPROP 2 LAST PATH I126
J 0
(-4850 5450);
DISPLAY 1.021277 (-4850 5450);
DISPLAY INVISIBLE (-4850 5450);
FORCEPROP 1 LAST COMMENT_BODY TRUE
J 0
(-5225 5300);
DISPLAY 0.872340 (-5225 5300);
PAINT GREEN (-5225 5300);
DISPLAY INVISIBLE (-5225 5300);
FORCEPROP 1 LAST OFFPAGE TRUE
J 0
(-4850 5275);
DISPLAY 0.872340 (-4850 5275);
PAINT GREEN (-4850 5275);
DISPLAY INVISIBLE (-4850 5275);
FORCEPROP 2 LAST CDS_LIB mstr_standard
J 0
(-5175 5400);
DISPLAY 0.723404 (-5175 5400);
PAINT MONO (-5175 5400);
DISPLAY INVISIBLE (-5175 5400);
FORCEADD OFFPAGE..5
(-6975 1300);
FORCEPROP 2 LAST $XR0 103 
J 0
(-7230 1300);
DISPLAY 0.638298 (-7230 1300);
PAINT MONO (-7230 1300);
FORCEPROP 2 LAST PATH I127
J 0
(-7225 1350);
DISPLAY 1.021277 (-7225 1350);
DISPLAY INVISIBLE (-7225 1350);
FORCEPROP 1 LAST COMMENT_BODY TRUE
J 0
(-6875 1225);
DISPLAY 0.872340 (-6875 1225);
PAINT GREEN (-6875 1225);
DISPLAY INVISIBLE (-6875 1225);
FORCEPROP 1 LAST OFFPAGE TRUE
J 0
(-6650 1175);
DISPLAY 0.872340 (-6650 1175);
PAINT GREEN (-6650 1175);
DISPLAY INVISIBLE (-6650 1175);
FORCEPROP 2 LAST BOM_COST MEM
J 0
(-7050 1375);
DISPLAY 0.808511 (-7050 1375);
DISPLAY INVISIBLE (-7050 1375);
FORCEPROP 2 LAST CDS_LIB mstr_standard
J 0
(-6975 1300);
DISPLAY 0.808511 (-6975 1300);
DISPLAY INVISIBLE (-6975 1300);
FORCEADD GND..1
(-6200 900);
FORCEPROP 3 LASTPIN (-6200 950) SIG_NAME GND\g
J 0
(-6190 960);
DISPLAY 0.659574 (-6190 960);
PAINT MONO (-6190 960);
DISPLAY INVISIBLE (-6190 960);
FORCEPROP 1 LAST SIZE 1B
J 0
(-6125 850);
DISPLAY 0.851064 (-6125 850);
PAINT GREEN (-6125 850);
DISPLAY INVISIBLE (-6125 850);
FORCEPROP 2 LAST BOM_COST MEM
J 0
(-6300 975);
DISPLAY 0.808511 (-6300 975);
DISPLAY INVISIBLE (-6300 975);
FORCEPROP 2 LAST CDS_LIB mstr_symbols
J 0
(-6200 900);
DISPLAY 0.808511 (-6200 900);
DISPLAY INVISIBLE (-6200 900);
FORCEPROP 1 LAST BODY_TYPE PLUMBING
J 0
(-6245 857);
DISPLAY 0.340426 (-6245 857);
PAINT GREEN (-6245 857);
DISPLAY INVISIBLE (-6245 857);
FORCEPROP 1 LAST PATH I128
J 0
(-6125 900);
DISPLAY 0.872340 (-6125 900);
PAINT AQUA (-6125 900);
DISPLAY INVISIBLE (-6125 900);
FORCEPROP 1 LAST VOLTAGE 0.0
J 0
(-6245 857);
DISPLAY 0.723404 (-6245 857);
PAINT SKYBLUE (-6245 857);
DISPLAY INVISIBLE (-6245 857);
FORCEPROP 1 LAST HDL_POWER GND
J 0
(-6200 1050);
DISPLAY 0.851064 (-6200 1050);
PAINT GREEN (-6200 1050);
DISPLAY INVISIBLE (-6200 1050);
FORCEADD Q_RES..2
(-6200 1125);
FORCEPROP 1 LAST LOCATION R37
J 0
(-6155 1250);
DISPLAY 0.489362 (-6155 1250);
PAINT SKYBLUE (-6155 1250);
FORCEPROP 2 LAST SEC 1
J 0
(-6150 1350);
DISPLAY 0.808511 (-6150 1350);
PAINT MONO (-6150 1350);
DISPLAY INVISIBLE (-6150 1350);
FORCEPROP 1 LASTPIN (-6200 1225) $PN 1
J 0
(-6195 1187);
DISPLAY 0.489362 (-6195 1187);
PAINT WHITE (-6195 1187);
FORCEPROP 1 LASTPIN (-6200 1025) $PN 2
J 0
(-6195 1035);
DISPLAY 0.489362 (-6195 1035);
PAINT WHITE (-6195 1035);
FORCEPROP 0 LASTPIN (-6200 1225) XNET_PINS 3
R 1
J 0
(-6210 1235);
DISPLAY 0.808511 (-6210 1235);
PAINT MONO (-6210 1235);
DISPLAY INVISIBLE (-6210 1235);
FORCEPROP 0 LASTPIN (-6200 1025) XNET_PINS 2
R 1
J 2
(-6210 1015);
DISPLAY 0.808511 (-6210 1015);
PAINT MONO (-6210 1015);
DISPLAY INVISIBLE (-6210 1015);
FORCEPROP 1 LAST WATTAGE 1/16W
J 0
(-6160 1100);
DISPLAY 0.489362 (-6160 1100);
PAINT SKYBLUE (-6160 1100);
FORCEPROP 1 LAST MATERIAL CHIP
J 0
(-6160 1050);
DISPLAY 0.489362 (-6160 1050);
PAINT SKYBLUE (-6160 1050);
FORCEPROP 1 LAST TOLERANCE 1%
J 0
(-6155 1150);
DISPLAY 0.489362 (-6155 1150);
PAINT SKYBLUE (-6155 1150);
FORCEPROP 1 LAST VALUE 10K
J 0
(-6155 1200);
DISPLAY 0.489362 (-6155 1200);
PAINT SKYBLUE (-6155 1200);
FORCEPROP 1 LAST PART_NUMBER CS31002FB08
J 0
(-6160 1000);
DISPLAY 0.489362 (-6160 1000);
PAINT SKYBLUE (-6160 1000);
FORCEPROP 1 LAST PACK_TYPE 0402LF
J 0
(-6160 950);
DISPLAY 0.489362 (-6160 950);
PAINT SKYBLUE (-6160 950);
FORCEPROP 2 LAST BOM_COST MEM
J 0
(-6150 1300);
DISPLAY 0.808511 (-6150 1300);
DISPLAY INVISIBLE (-6150 1300);
FORCEPROP 2 LAST CDS_LIB pure_quanta
J 0
(-6200 1125);
DISPLAY INVISIBLE (-6200 1125);
FORCEPROP 2 LAST SEC_TYPE 0402LF
J 0
(-6150 1350);
DISPLAY 0.808511 (-6150 1350);
PAINT MONO (-6150 1350);
DISPLAY INVISIBLE (-6150 1350);
FORCEPROP 1 LAST PATH I129
J 0
(-6150 1300);
DISPLAY 0.978723 (-6150 1300);
PAINT WHITE (-6150 1300);
DISPLAY INVISIBLE (-6150 1300);
FORCEPROP 2 LAST ROOM MEM_CH_A_CPU1_DIMM1
J 0
(-6150 1350);
DISPLAY 0.808511 (-6150 1350);
PAINT RED (-6150 1350);
DISPLAY INVISIBLE (-6150 1350);
FORCEADD OFFPAGE..1
(-8075 4100);
FORCEPROP 2 LAST $XR0 43 
J 0
(-8296 4100);
DISPLAY 0.638298 (-8296 4100);
PAINT MONO (-8296 4100);
FORCEPROP 2 LAST PATH I13
J 0
(-8325 4150);
DISPLAY 1.021277 (-8325 4150);
DISPLAY INVISIBLE (-8325 4150);
FORCEPROP 1 LAST COMMENT_BODY TRUE
J 0
(-7950 4000);
DISPLAY 0.872340 (-7950 4000);
PAINT GREEN (-7950 4000);
DISPLAY INVISIBLE (-7950 4000);
FORCEPROP 1 LAST OFFPAGE TRUE
J 0
(-7750 3975);
DISPLAY 0.872340 (-7750 3975);
PAINT GREEN (-7750 3975);
DISPLAY INVISIBLE (-7750 3975);
FORCEPROP 2 LAST CDS_LIB mstr_standard
J 0
(-8075 4100);
DISPLAY 0.723404 (-8075 4100);
PAINT MONO (-8075 4100);
DISPLAY INVISIBLE (-8075 4100);
FORCEADD OFFPAGE..1
(-8075 4250);
FORCEPROP 2 LAST $XR0 43 
J 0
(-8296 4250);
DISPLAY 0.638298 (-8296 4250);
PAINT MONO (-8296 4250);
FORCEPROP 2 LAST PATH I14
J 0
(-8325 4300);
DISPLAY 1.021277 (-8325 4300);
DISPLAY INVISIBLE (-8325 4300);
FORCEPROP 1 LAST COMMENT_BODY TRUE
J 0
(-7950 4150);
DISPLAY 0.872340 (-7950 4150);
PAINT GREEN (-7950 4150);
DISPLAY INVISIBLE (-7950 4150);
FORCEPROP 1 LAST OFFPAGE TRUE
J 0
(-7750 4125);
DISPLAY 0.872340 (-7750 4125);
PAINT GREEN (-7750 4125);
DISPLAY INVISIBLE (-7750 4125);
FORCEPROP 2 LAST CDS_LIB mstr_standard
J 0
(-8075 4250);
DISPLAY 0.723404 (-8075 4250);
PAINT MONO (-8075 4250);
DISPLAY INVISIBLE (-8075 4250);
FORCEADD GND..1
(-2125 1875);
FORCEPROP 3 LASTPIN (-2125 1925) SIG_NAME GND\g
J 0
(-2115 1935);
DISPLAY 0.659574 (-2115 1935);
PAINT MONO (-2115 1935);
DISPLAY INVISIBLE (-2115 1935);
FORCEPROP 2 LAST CDS_LIB mstr_symbols
J 0
(-2125 1875);
DISPLAY 0.723404 (-2125 1875);
DISPLAY INVISIBLE (-2125 1875);
FORCEPROP 1 LAST SIZE 1B
J 0
(-2050 1825);
DISPLAY 0.851064 (-2050 1825);
PAINT GREEN (-2050 1825);
DISPLAY INVISIBLE (-2050 1825);
FORCEPROP 1 LAST BODY_TYPE PLUMBING
J 0
(-2170 1832);
DISPLAY 0.340426 (-2170 1832);
PAINT GREEN (-2170 1832);
DISPLAY INVISIBLE (-2170 1832);
FORCEPROP 1 LAST PATH I140
J 0
(-2050 1875);
DISPLAY 0.872340 (-2050 1875);
PAINT AQUA (-2050 1875);
DISPLAY INVISIBLE (-2050 1875);
FORCEPROP 1 LAST VOLTAGE 0.0
J 0
(-2170 1832);
DISPLAY 0.723404 (-2170 1832);
PAINT SKYBLUE (-2170 1832);
DISPLAY INVISIBLE (-2170 1832);
FORCEPROP 1 LAST HDL_POWER GND
J 0
(-2125 2025);
DISPLAY 0.851064 (-2125 2025);
PAINT GREEN (-2125 2025);
DISPLAY INVISIBLE (-2125 2025);
FORCEADD GND..1
(-525 1675);
FORCEPROP 3 LASTPIN (-525 1725) SIG_NAME GND\g
J 0
(-515 1735);
DISPLAY 0.659574 (-515 1735);
PAINT MONO (-515 1735);
DISPLAY INVISIBLE (-515 1735);
FORCEPROP 2 LAST CDS_LIB mstr_symbols
J 0
(-525 1675);
DISPLAY 0.723404 (-525 1675);
DISPLAY INVISIBLE (-525 1675);
FORCEPROP 1 LAST SIZE 1B
J 0
(-450 1625);
DISPLAY 0.851064 (-450 1625);
PAINT GREEN (-450 1625);
DISPLAY INVISIBLE (-450 1625);
FORCEPROP 1 LAST BODY_TYPE PLUMBING
J 0
(-570 1632);
DISPLAY 0.340426 (-570 1632);
PAINT GREEN (-570 1632);
DISPLAY INVISIBLE (-570 1632);
FORCEPROP 1 LAST PATH I141
J 0
(-450 1675);
DISPLAY 0.872340 (-450 1675);
PAINT AQUA (-450 1675);
DISPLAY INVISIBLE (-450 1675);
FORCEPROP 1 LAST VOLTAGE 0.0
J 0
(-570 1632);
DISPLAY 0.723404 (-570 1632);
PAINT SKYBLUE (-570 1632);
DISPLAY INVISIBLE (-570 1632);
FORCEPROP 1 LAST HDL_POWER GND
J 0
(-525 1825);
DISPLAY 0.851064 (-525 1825);
PAINT GREEN (-525 1825);
DISPLAY INVISIBLE (-525 1825);
FORCEADD SCONN288_DDR506112002KQ..3
(-1325 3625);
FORCEPROP 1 LAST LOCATION J102
J 0
(-1775 5600);
DISPLAY 0.468085 (-1775 5600);
PAINT SKYBLUE (-1775 5600);
FORCEPROP 0 LAST $SEC 3
J 0
(-1775 5750);
DISPLAY 0.680851 (-1775 5750);
PAINT MONO (-1775 5750);
DISPLAY INVISIBLE (-1775 5750);
FORCEPROP 0 LAST CDS_SEC 3
J 0
(-1775 5750);
DISPLAY 0.680851 (-1775 5750);
DISPLAY INVISIBLE (-1775 5750);
FORCEPROP 0 LASTPIN (-725 2025) $PN G1
J 0
(-715 2035);
DISPLAY 0.680851 (-715 2035);
PAINT MONO (-715 2035);
FORCEPROP 0 LASTPIN (-725 1975) $PN G2
J 0
(-715 1985);
DISPLAY 0.680851 (-715 1985);
PAINT MONO (-715 1985);
FORCEPROP 0 LASTPIN (-725 1925) $PN G3
J 0
(-715 1935);
DISPLAY 0.680851 (-715 1935);
PAINT MONO (-715 1935);
FORCEPROP 0 LASTPIN (-1925 5175) $PN 1
J 2
(-1935 5185);
DISPLAY 0.680851 (-1935 5185);
PAINT MONO (-1935 5185);
FORCEPROP 0 LASTPIN (-1925 5225) $PN 145
J 2
(-1935 5235);
DISPLAY 0.680851 (-1935 5235);
PAINT MONO (-1935 5235);
FORCEPROP 0 LASTPIN (-1925 5275) $PN 146
J 2
(-1935 5285);
DISPLAY 0.680851 (-1935 5285);
PAINT MONO (-1935 5285);
FORCEPROP 0 LASTPIN (-725 2125) $PN 6
J 0
(-715 2135);
DISPLAY 0.680851 (-715 2135);
PAINT MONO (-715 2135);
FORCEPROP 0 LASTPIN (-725 2175) $PN 8
J 0
(-715 2185);
DISPLAY 0.680851 (-715 2185);
PAINT MONO (-715 2185);
FORCEPROP 0 LASTPIN (-725 2225) $PN 10
J 0
(-715 2235);
DISPLAY 0.680851 (-715 2235);
PAINT MONO (-715 2235);
FORCEPROP 0 LASTPIN (-725 2275) $PN 13
J 0
(-715 2285);
DISPLAY 0.680851 (-715 2285);
PAINT MONO (-715 2285);
FORCEPROP 0 LASTPIN (-725 2325) $PN 15
J 0
(-715 2335);
DISPLAY 0.680851 (-715 2335);
PAINT MONO (-715 2335);
FORCEPROP 0 LASTPIN (-725 2375) $PN 17
J 0
(-715 2385);
DISPLAY 0.680851 (-715 2385);
PAINT MONO (-715 2385);
FORCEPROP 0 LASTPIN (-725 2425) $PN 19
J 0
(-715 2435);
DISPLAY 0.680851 (-715 2435);
PAINT MONO (-715 2435);
FORCEPROP 0 LASTPIN (-725 2475) $PN 21
J 0
(-715 2485);
DISPLAY 0.680851 (-715 2485);
PAINT MONO (-715 2485);
FORCEPROP 0 LASTPIN (-725 2525) $PN 24
J 0
(-715 2535);
DISPLAY 0.680851 (-715 2535);
PAINT MONO (-715 2535);
FORCEPROP 0 LASTPIN (-725 2575) $PN 26
J 0
(-715 2585);
DISPLAY 0.680851 (-715 2585);
PAINT MONO (-715 2585);
FORCEPROP 0 LASTPIN (-725 2625) $PN 28
J 0
(-715 2635);
DISPLAY 0.680851 (-715 2635);
PAINT MONO (-715 2635);
FORCEPROP 0 LASTPIN (-725 2675) $PN 30
J 0
(-715 2685);
DISPLAY 0.680851 (-715 2685);
PAINT MONO (-715 2685);
FORCEPROP 0 LASTPIN (-725 2725) $PN 32
J 0
(-715 2735);
DISPLAY 0.680851 (-715 2735);
PAINT MONO (-715 2735);
FORCEPROP 0 LASTPIN (-725 2775) $PN 35
J 0
(-715 2785);
DISPLAY 0.680851 (-715 2785);
PAINT MONO (-715 2785);
FORCEPROP 0 LASTPIN (-725 2825) $PN 37
J 0
(-715 2835);
DISPLAY 0.680851 (-715 2835);
PAINT MONO (-715 2835);
FORCEPROP 0 LASTPIN (-725 2875) $PN 39
J 0
(-715 2885);
DISPLAY 0.680851 (-715 2885);
PAINT MONO (-715 2885);
FORCEPROP 0 LASTPIN (-725 2925) $PN 41
J 0
(-715 2935);
DISPLAY 0.680851 (-715 2935);
PAINT MONO (-715 2935);
FORCEPROP 0 LASTPIN (-725 2975) $PN 43
J 0
(-715 2985);
DISPLAY 0.680851 (-715 2985);
PAINT MONO (-715 2985);
FORCEPROP 0 LASTPIN (-725 3025) $PN 46
J 0
(-715 3035);
DISPLAY 0.680851 (-715 3035);
PAINT MONO (-715 3035);
FORCEPROP 0 LASTPIN (-725 3075) $PN 48
J 0
(-715 3085);
DISPLAY 0.680851 (-715 3085);
PAINT MONO (-715 3085);
FORCEPROP 0 LASTPIN (-725 3125) $PN 50
J 0
(-715 3135);
DISPLAY 0.680851 (-715 3135);
PAINT MONO (-715 3135);
FORCEPROP 0 LASTPIN (-725 3175) $PN 52
J 0
(-715 3185);
DISPLAY 0.680851 (-715 3185);
PAINT MONO (-715 3185);
FORCEPROP 0 LASTPIN (-725 3225) $PN 54
J 0
(-715 3235);
DISPLAY 0.680851 (-715 3235);
PAINT MONO (-715 3235);
FORCEPROP 0 LASTPIN (-725 3275) $PN 57
J 0
(-715 3285);
DISPLAY 0.680851 (-715 3285);
PAINT MONO (-715 3285);
FORCEPROP 0 LASTPIN (-725 3325) $PN 59
J 0
(-715 3335);
DISPLAY 0.680851 (-715 3335);
PAINT MONO (-715 3335);
FORCEPROP 0 LASTPIN (-725 3375) $PN 61
J 0
(-715 3385);
DISPLAY 0.680851 (-715 3385);
PAINT MONO (-715 3385);
FORCEPROP 0 LASTPIN (-725 3425) $PN 63
J 0
(-715 3435);
DISPLAY 0.680851 (-715 3435);
PAINT MONO (-715 3435);
FORCEPROP 0 LASTPIN (-725 3475) $PN 65
J 0
(-715 3485);
DISPLAY 0.680851 (-715 3485);
PAINT MONO (-715 3485);
FORCEPROP 0 LASTPIN (-725 3525) $PN 67
J 0
(-715 3535);
DISPLAY 0.680851 (-715 3535);
PAINT MONO (-715 3535);
FORCEPROP 0 LASTPIN (-725 3575) $PN 69
J 0
(-715 3585);
DISPLAY 0.680851 (-715 3585);
PAINT MONO (-715 3585);
FORCEPROP 0 LASTPIN (-725 3625) $PN 71
J 0
(-715 3635);
DISPLAY 0.680851 (-715 3635);
PAINT MONO (-715 3635);
FORCEPROP 0 LASTPIN (-725 3675) $PN 73
J 0
(-715 3685);
DISPLAY 0.680851 (-715 3685);
PAINT MONO (-715 3685);
FORCEPROP 0 LASTPIN (-725 3725) $PN 75
J 0
(-715 3735);
DISPLAY 0.680851 (-715 3735);
PAINT MONO (-715 3735);
FORCEPROP 0 LASTPIN (-725 3775) $PN 77
J 0
(-715 3785);
DISPLAY 0.680851 (-715 3785);
PAINT MONO (-715 3785);
FORCEPROP 0 LASTPIN (-725 3825) $PN 79
J 0
(-715 3835);
DISPLAY 0.680851 (-715 3835);
PAINT MONO (-715 3835);
FORCEPROP 0 LASTPIN (-725 3875) $PN 81
J 0
(-715 3885);
DISPLAY 0.680851 (-715 3885);
PAINT MONO (-715 3885);
FORCEPROP 0 LASTPIN (-725 3925) $PN 83
J 0
(-715 3935);
DISPLAY 0.680851 (-715 3935);
PAINT MONO (-715 3935);
FORCEPROP 0 LASTPIN (-725 3975) $PN 85
J 0
(-715 3985);
DISPLAY 0.680851 (-715 3985);
PAINT MONO (-715 3985);
FORCEPROP 0 LASTPIN (-725 4025) $PN 88
J 0
(-715 4035);
DISPLAY 0.680851 (-715 4035);
PAINT MONO (-715 4035);
FORCEPROP 0 LASTPIN (-725 4075) $PN 90
J 0
(-715 4085);
DISPLAY 0.680851 (-715 4085);
PAINT MONO (-715 4085);
FORCEPROP 0 LASTPIN (-725 4125) $PN 92
J 0
(-715 4135);
DISPLAY 0.680851 (-715 4135);
PAINT MONO (-715 4135);
FORCEPROP 0 LASTPIN (-725 4175) $PN 95
J 0
(-715 4185);
DISPLAY 0.680851 (-715 4185);
PAINT MONO (-715 4185);
FORCEPROP 0 LASTPIN (-725 4225) $PN 97
J 0
(-715 4235);
DISPLAY 0.680851 (-715 4235);
PAINT MONO (-715 4235);
FORCEPROP 0 LASTPIN (-725 4275) $PN 99
J 0
(-715 4285);
DISPLAY 0.680851 (-715 4285);
PAINT MONO (-715 4285);
FORCEPROP 0 LASTPIN (-725 4325) $PN 101
J 0
(-715 4335);
DISPLAY 0.680851 (-715 4335);
PAINT MONO (-715 4335);
FORCEPROP 0 LASTPIN (-725 4375) $PN 103
J 0
(-715 4385);
DISPLAY 0.680851 (-715 4385);
PAINT MONO (-715 4385);
FORCEPROP 0 LASTPIN (-725 4425) $PN 106
J 0
(-715 4435);
DISPLAY 0.680851 (-715 4435);
PAINT MONO (-715 4435);
FORCEPROP 0 LASTPIN (-725 4475) $PN 108
J 0
(-715 4485);
DISPLAY 0.680851 (-715 4485);
PAINT MONO (-715 4485);
FORCEPROP 0 LASTPIN (-725 4525) $PN 110
J 0
(-715 4535);
DISPLAY 0.680851 (-715 4535);
PAINT MONO (-715 4535);
FORCEPROP 0 LASTPIN (-725 4575) $PN 112
J 0
(-715 4585);
DISPLAY 0.680851 (-715 4585);
PAINT MONO (-715 4585);
FORCEPROP 0 LASTPIN (-725 4625) $PN 114
J 0
(-715 4635);
DISPLAY 0.680851 (-715 4635);
PAINT MONO (-715 4635);
FORCEPROP 0 LASTPIN (-725 4675) $PN 117
J 0
(-715 4685);
DISPLAY 0.680851 (-715 4685);
PAINT MONO (-715 4685);
FORCEPROP 0 LASTPIN (-725 4725) $PN 119
J 0
(-715 4735);
DISPLAY 0.680851 (-715 4735);
PAINT MONO (-715 4735);
FORCEPROP 0 LASTPIN (-725 4775) $PN 121
J 0
(-715 4785);
DISPLAY 0.680851 (-715 4785);
PAINT MONO (-715 4785);
FORCEPROP 0 LASTPIN (-725 4825) $PN 123
J 0
(-715 4835);
DISPLAY 0.680851 (-715 4835);
PAINT MONO (-715 4835);
FORCEPROP 0 LASTPIN (-725 4875) $PN 125
J 0
(-715 4885);
DISPLAY 0.680851 (-715 4885);
PAINT MONO (-715 4885);
FORCEPROP 0 LASTPIN (-725 4925) $PN 128
J 0
(-715 4935);
DISPLAY 0.680851 (-715 4935);
PAINT MONO (-715 4935);
FORCEPROP 0 LASTPIN (-725 4975) $PN 130
J 0
(-715 4985);
DISPLAY 0.680851 (-715 4985);
PAINT MONO (-715 4985);
FORCEPROP 0 LASTPIN (-725 5025) $PN 132
J 0
(-715 5035);
DISPLAY 0.680851 (-715 5035);
PAINT MONO (-715 5035);
FORCEPROP 0 LASTPIN (-725 5075) $PN 134
J 0
(-715 5085);
DISPLAY 0.680851 (-715 5085);
PAINT MONO (-715 5085);
FORCEPROP 0 LASTPIN (-725 5125) $PN 136
J 0
(-715 5135);
DISPLAY 0.680851 (-715 5135);
PAINT MONO (-715 5135);
FORCEPROP 0 LASTPIN (-725 5175) $PN 139
J 0
(-715 5185);
DISPLAY 0.680851 (-715 5185);
PAINT MONO (-715 5185);
FORCEPROP 0 LASTPIN (-725 5225) $PN 141
J 0
(-715 5235);
DISPLAY 0.680851 (-715 5235);
PAINT MONO (-715 5235);
FORCEPROP 0 LASTPIN (-725 5275) $PN 143
J 0
(-715 5285);
DISPLAY 0.680851 (-715 5285);
PAINT MONO (-715 5285);
FORCEPROP 0 LASTPIN (-1925 2025) $PN 151
J 2
(-1935 2035);
DISPLAY 0.680851 (-1935 2035);
PAINT MONO (-1935 2035);
FORCEPROP 0 LASTPIN (-1925 2075) $PN 153
J 2
(-1935 2085);
DISPLAY 0.680851 (-1935 2085);
PAINT MONO (-1935 2085);
FORCEPROP 0 LASTPIN (-1925 2125) $PN 155
J 2
(-1935 2135);
DISPLAY 0.680851 (-1935 2135);
PAINT MONO (-1935 2135);
FORCEPROP 0 LASTPIN (-1925 2175) $PN 158
J 2
(-1935 2185);
DISPLAY 0.680851 (-1935 2185);
PAINT MONO (-1935 2185);
FORCEPROP 0 LASTPIN (-1925 2225) $PN 160
J 2
(-1935 2235);
DISPLAY 0.680851 (-1935 2235);
PAINT MONO (-1935 2235);
FORCEPROP 0 LASTPIN (-1925 2275) $PN 162
J 2
(-1935 2285);
DISPLAY 0.680851 (-1935 2285);
PAINT MONO (-1935 2285);
FORCEPROP 0 LASTPIN (-1925 2325) $PN 164
J 2
(-1935 2335);
DISPLAY 0.680851 (-1935 2335);
PAINT MONO (-1935 2335);
FORCEPROP 0 LASTPIN (-1925 2375) $PN 166
J 2
(-1935 2385);
DISPLAY 0.680851 (-1935 2385);
PAINT MONO (-1935 2385);
FORCEPROP 0 LASTPIN (-1925 2425) $PN 169
J 2
(-1935 2435);
DISPLAY 0.680851 (-1935 2435);
PAINT MONO (-1935 2435);
FORCEPROP 0 LASTPIN (-1925 2475) $PN 171
J 2
(-1935 2485);
DISPLAY 0.680851 (-1935 2485);
PAINT MONO (-1935 2485);
FORCEPROP 0 LASTPIN (-1925 2525) $PN 173
J 2
(-1935 2535);
DISPLAY 0.680851 (-1935 2535);
PAINT MONO (-1935 2535);
FORCEPROP 0 LASTPIN (-1925 2575) $PN 175
J 2
(-1935 2585);
DISPLAY 0.680851 (-1935 2585);
PAINT MONO (-1935 2585);
FORCEPROP 0 LASTPIN (-1925 2625) $PN 177
J 2
(-1935 2635);
DISPLAY 0.680851 (-1935 2635);
PAINT MONO (-1935 2635);
FORCEPROP 0 LASTPIN (-1925 2675) $PN 180
J 2
(-1935 2685);
DISPLAY 0.680851 (-1935 2685);
PAINT MONO (-1935 2685);
FORCEPROP 0 LASTPIN (-1925 2725) $PN 182
J 2
(-1935 2735);
DISPLAY 0.680851 (-1935 2735);
PAINT MONO (-1935 2735);
FORCEPROP 0 LASTPIN (-1925 2775) $PN 184
J 2
(-1935 2785);
DISPLAY 0.680851 (-1935 2785);
PAINT MONO (-1935 2785);
FORCEPROP 0 LASTPIN (-1925 2825) $PN 186
J 2
(-1935 2835);
DISPLAY 0.680851 (-1935 2835);
PAINT MONO (-1935 2835);
FORCEPROP 0 LASTPIN (-1925 2875) $PN 188
J 2
(-1935 2885);
DISPLAY 0.680851 (-1935 2885);
PAINT MONO (-1935 2885);
FORCEPROP 0 LASTPIN (-1925 2925) $PN 191
J 2
(-1935 2935);
DISPLAY 0.680851 (-1935 2935);
PAINT MONO (-1935 2935);
FORCEPROP 0 LASTPIN (-1925 2975) $PN 193
J 2
(-1935 2985);
DISPLAY 0.680851 (-1935 2985);
PAINT MONO (-1935 2985);
FORCEPROP 0 LASTPIN (-1925 3025) $PN 195
J 2
(-1935 3035);
DISPLAY 0.680851 (-1935 3035);
PAINT MONO (-1935 3035);
FORCEPROP 0 LASTPIN (-1925 3075) $PN 197
J 2
(-1935 3085);
DISPLAY 0.680851 (-1935 3085);
PAINT MONO (-1935 3085);
FORCEPROP 0 LASTPIN (-1925 3125) $PN 199
J 2
(-1935 3135);
DISPLAY 0.680851 (-1935 3135);
PAINT MONO (-1935 3135);
FORCEPROP 0 LASTPIN (-1925 3175) $PN 202
J 2
(-1935 3185);
DISPLAY 0.680851 (-1935 3185);
PAINT MONO (-1935 3185);
FORCEPROP 0 LASTPIN (-1925 3225) $PN 204
J 2
(-1935 3235);
DISPLAY 0.680851 (-1935 3235);
PAINT MONO (-1935 3235);
FORCEPROP 0 LASTPIN (-1925 3275) $PN 206
J 2
(-1935 3285);
DISPLAY 0.680851 (-1935 3285);
PAINT MONO (-1935 3285);
FORCEPROP 0 LASTPIN (-1925 3325) $PN 208
J 2
(-1935 3335);
DISPLAY 0.680851 (-1935 3335);
PAINT MONO (-1935 3335);
FORCEPROP 0 LASTPIN (-1925 3375) $PN 210
J 2
(-1935 3385);
DISPLAY 0.680851 (-1935 3385);
PAINT MONO (-1935 3385);
FORCEPROP 0 LASTPIN (-1925 3425) $PN 212
J 2
(-1935 3435);
DISPLAY 0.680851 (-1935 3435);
PAINT MONO (-1935 3435);
FORCEPROP 0 LASTPIN (-1925 3475) $PN 214
J 2
(-1935 3485);
DISPLAY 0.680851 (-1935 3485);
PAINT MONO (-1935 3485);
FORCEPROP 0 LASTPIN (-1925 3525) $PN 216
J 2
(-1935 3535);
DISPLAY 0.680851 (-1935 3535);
PAINT MONO (-1935 3535);
FORCEPROP 0 LASTPIN (-1925 3575) $PN 219
J 2
(-1935 3585);
DISPLAY 0.680851 (-1935 3585);
PAINT MONO (-1935 3585);
FORCEPROP 0 LASTPIN (-1925 3625) $PN 222
J 2
(-1935 3635);
DISPLAY 0.680851 (-1935 3635);
PAINT MONO (-1935 3635);
FORCEPROP 0 LASTPIN (-1925 3675) $PN 224
J 2
(-1935 3685);
DISPLAY 0.680851 (-1935 3685);
PAINT MONO (-1935 3685);
FORCEPROP 0 LASTPIN (-1925 3725) $PN 226
J 2
(-1935 3735);
DISPLAY 0.680851 (-1935 3735);
PAINT MONO (-1935 3735);
FORCEPROP 0 LASTPIN (-1925 3775) $PN 228
J 2
(-1935 3785);
DISPLAY 0.680851 (-1935 3785);
PAINT MONO (-1935 3785);
FORCEPROP 0 LASTPIN (-1925 3825) $PN 230
J 2
(-1935 3835);
DISPLAY 0.680851 (-1935 3835);
PAINT MONO (-1935 3835);
FORCEPROP 0 LASTPIN (-1925 3875) $PN 233
J 2
(-1935 3885);
DISPLAY 0.680851 (-1935 3885);
PAINT MONO (-1935 3885);
FORCEPROP 0 LASTPIN (-1925 3925) $PN 235
J 2
(-1935 3935);
DISPLAY 0.680851 (-1935 3935);
PAINT MONO (-1935 3935);
FORCEPROP 0 LASTPIN (-1925 3975) $PN 237
J 2
(-1935 3985);
DISPLAY 0.680851 (-1935 3985);
PAINT MONO (-1935 3985);
FORCEPROP 0 LASTPIN (-1925 4025) $PN 240
J 2
(-1935 4035);
DISPLAY 0.680851 (-1935 4035);
PAINT MONO (-1935 4035);
FORCEPROP 0 LASTPIN (-1925 4075) $PN 242
J 2
(-1935 4085);
DISPLAY 0.680851 (-1935 4085);
PAINT MONO (-1935 4085);
FORCEPROP 0 LASTPIN (-1925 4125) $PN 244
J 2
(-1935 4135);
DISPLAY 0.680851 (-1935 4135);
PAINT MONO (-1935 4135);
FORCEPROP 0 LASTPIN (-1925 4175) $PN 246
J 2
(-1935 4185);
DISPLAY 0.680851 (-1935 4185);
PAINT MONO (-1935 4185);
FORCEPROP 0 LASTPIN (-1925 4225) $PN 248
J 2
(-1935 4235);
DISPLAY 0.680851 (-1935 4235);
PAINT MONO (-1935 4235);
FORCEPROP 0 LASTPIN (-1925 4275) $PN 251
J 2
(-1935 4285);
DISPLAY 0.680851 (-1935 4285);
PAINT MONO (-1935 4285);
FORCEPROP 0 LASTPIN (-1925 4325) $PN 253
J 2
(-1935 4335);
DISPLAY 0.680851 (-1935 4335);
PAINT MONO (-1935 4335);
FORCEPROP 0 LASTPIN (-1925 4375) $PN 255
J 2
(-1935 4385);
DISPLAY 0.680851 (-1935 4385);
PAINT MONO (-1935 4385);
FORCEPROP 0 LASTPIN (-1925 4425) $PN 257
J 2
(-1935 4435);
DISPLAY 0.680851 (-1935 4435);
PAINT MONO (-1935 4435);
FORCEPROP 0 LASTPIN (-1925 4475) $PN 259
J 2
(-1935 4485);
DISPLAY 0.680851 (-1935 4485);
PAINT MONO (-1935 4485);
FORCEPROP 0 LASTPIN (-1925 4525) $PN 262
J 2
(-1935 4535);
DISPLAY 0.680851 (-1935 4535);
PAINT MONO (-1935 4535);
FORCEPROP 0 LASTPIN (-1925 4575) $PN 264
J 2
(-1935 4585);
DISPLAY 0.680851 (-1935 4585);
PAINT MONO (-1935 4585);
FORCEPROP 0 LASTPIN (-1925 4625) $PN 266
J 2
(-1935 4635);
DISPLAY 0.680851 (-1935 4635);
PAINT MONO (-1935 4635);
FORCEPROP 0 LASTPIN (-1925 4675) $PN 268
J 2
(-1935 4685);
DISPLAY 0.680851 (-1935 4685);
PAINT MONO (-1935 4685);
FORCEPROP 0 LASTPIN (-1925 4725) $PN 270
J 2
(-1935 4735);
DISPLAY 0.680851 (-1935 4735);
PAINT MONO (-1935 4735);
FORCEPROP 0 LASTPIN (-1925 4775) $PN 273
J 2
(-1935 4785);
DISPLAY 0.680851 (-1935 4785);
PAINT MONO (-1935 4785);
FORCEPROP 0 LASTPIN (-1925 4825) $PN 275
J 2
(-1935 4835);
DISPLAY 0.680851 (-1935 4835);
PAINT MONO (-1935 4835);
FORCEPROP 0 LASTPIN (-1925 4875) $PN 277
J 2
(-1935 4885);
DISPLAY 0.680851 (-1935 4885);
PAINT MONO (-1935 4885);
FORCEPROP 0 LASTPIN (-1925 4925) $PN 279
J 2
(-1935 4935);
DISPLAY 0.680851 (-1935 4935);
PAINT MONO (-1935 4935);
FORCEPROP 0 LASTPIN (-1925 4975) $PN 281
J 2
(-1935 4985);
DISPLAY 0.680851 (-1935 4985);
PAINT MONO (-1935 4985);
FORCEPROP 0 LASTPIN (-1925 5025) $PN 284
J 2
(-1935 5035);
DISPLAY 0.680851 (-1935 5035);
PAINT MONO (-1935 5035);
FORCEPROP 0 LASTPIN (-1925 5075) $PN 286
J 2
(-1935 5085);
DISPLAY 0.680851 (-1935 5085);
PAINT MONO (-1935 5085);
FORCEPROP 0 LASTPIN (-1925 5125) $PN 288
J 2
(-1935 5135);
DISPLAY 0.680851 (-1935 5135);
PAINT MONO (-1935 5135);
FORCEPROP 2 LAST PART_TYPE SMLF
J 0
(-1775 5700);
DISPLAY 1.021277 (-1775 5700);
FORCEPROP 1 LAST MATERIAL IO
J 0
(-1775 5450);
DISPLAY 0.468085 (-1775 5450);
PAINT SKYBLUE (-1775 5450);
FORCEPROP 2 LAST VALUE SCONN288_DDR506112002KQ
J 0
(-1775 5650);
DISPLAY 0.489362 (-1775 5650);
PAINT SKYBLUE (-1775 5650);
FORCEPROP 1 LAST PART_NUMBER DFHST8FS479
J 0
(-1775 5525);
DISPLAY 0.468085 (-1775 5525);
PAINT SKYBLUE (-1775 5525);
FORCEPROP 1 LAST CDS_LMAN_SYM_OUTLINE -450,1800,450,-1750
J 0
(-1325 3625);
DISPLAY 0.468085 (-1325 3625);
PAINT GREEN (-1325 3625);
DISPLAY INVISIBLE (-1325 3625);
FORCEPROP 1 LAST PATH I142
J 0
(-1325 3625);
DISPLAY 0.723404 (-1325 3625);
PAINT GREEN (-1325 3625);
DISPLAY INVISIBLE (-1325 3625);
FORCEPROP 1 LAST NEEDS_NO_SIZE TRUE
J 0
(-1325 3625);
DISPLAY 0.723404 (-1325 3625);
PAINT GREEN (-1325 3625);
DISPLAY INVISIBLE (-1325 3625);
FORCEPROP 2 LAST CDS_LIB pure_quanta
J 0
(-1325 3625);
DISPLAY INVISIBLE (-1325 3625);
FORCEADD OFFPAGE..1
(-8075 4200);
FORCEPROP 2 LAST $XR0 43 
J 0
(-8296 4200);
DISPLAY 0.638298 (-8296 4200);
PAINT MONO (-8296 4200);
FORCEPROP 2 LAST PATH I15
J 0
(-8325 4250);
DISPLAY 1.021277 (-8325 4250);
DISPLAY INVISIBLE (-8325 4250);
FORCEPROP 1 LAST COMMENT_BODY TRUE
J 0
(-7950 4100);
DISPLAY 0.872340 (-7950 4100);
PAINT GREEN (-7950 4100);
DISPLAY INVISIBLE (-7950 4100);
FORCEPROP 1 LAST OFFPAGE TRUE
J 0
(-7750 4075);
DISPLAY 0.872340 (-7750 4075);
PAINT GREEN (-7750 4075);
DISPLAY INVISIBLE (-7750 4075);
FORCEPROP 2 LAST CDS_LIB mstr_standard
J 0
(-8075 4200);
DISPLAY 0.808511 (-8075 4200);
DISPLAY INVISIBLE (-8075 4200);
FORCEADD OFFPAGE..1
(-8075 4400);
FORCEPROP 2 LAST $XR0 43 
J 0
(-8296 4400);
DISPLAY 0.638298 (-8296 4400);
PAINT MONO (-8296 4400);
FORCEPROP 2 LAST PATH I16
J 0
(-8325 4450);
DISPLAY 1.021277 (-8325 4450);
DISPLAY INVISIBLE (-8325 4450);
FORCEPROP 1 LAST COMMENT_BODY TRUE
J 0
(-7950 4300);
DISPLAY 0.872340 (-7950 4300);
PAINT GREEN (-7950 4300);
DISPLAY INVISIBLE (-7950 4300);
FORCEPROP 1 LAST OFFPAGE TRUE
J 0
(-7750 4275);
DISPLAY 0.872340 (-7750 4275);
PAINT GREEN (-7750 4275);
DISPLAY INVISIBLE (-7750 4275);
FORCEPROP 2 LAST CDS_LIB mstr_standard
J 0
(-8075 4400);
DISPLAY 0.723404 (-8075 4400);
PAINT MONO (-8075 4400);
DISPLAY INVISIBLE (-8075 4400);
FORCEADD OFFPAGE..1
(-8075 4350);
FORCEPROP 2 LAST $XR0 43 
J 0
(-8296 4350);
DISPLAY 0.638298 (-8296 4350);
PAINT MONO (-8296 4350);
FORCEPROP 2 LAST PATH I17
J 0
(-8325 4400);
DISPLAY 1.021277 (-8325 4400);
DISPLAY INVISIBLE (-8325 4400);
FORCEPROP 1 LAST COMMENT_BODY TRUE
J 0
(-7950 4250);
DISPLAY 0.872340 (-7950 4250);
PAINT GREEN (-7950 4250);
DISPLAY INVISIBLE (-7950 4250);
FORCEPROP 1 LAST OFFPAGE TRUE
J 0
(-7750 4225);
DISPLAY 0.872340 (-7750 4225);
PAINT GREEN (-7750 4225);
DISPLAY INVISIBLE (-7750 4225);
FORCEPROP 2 LAST CDS_LIB mstr_standard
J 0
(-8075 4350);
DISPLAY 0.808511 (-8075 4350);
DISPLAY INVISIBLE (-8075 4350);
FORCEADD OFFPAGE..6
(-8075 2800);
FORCEPROP 2 LAST $XR5 136 
J 0
(-8955 2800);
DISPLAY 0.638298 (-8955 2800);
PAINT MONO (-8955 2800);
FORCEPROP 2 LAST $XR4 108 
J 0
(-8835 2800);
DISPLAY 0.638298 (-8835 2800);
PAINT MONO (-8835 2800);
FORCEPROP 2 LAST $XR3 107 
J 0
(-8715 2800);
DISPLAY 0.638298 (-8715 2800);
PAINT MONO (-8715 2800);
FORCEPROP 2 LAST $XR2 106 
J 0
(-8595 2800);
DISPLAY 0.638298 (-8595 2800);
PAINT MONO (-8595 2800);
FORCEPROP 2 LAST $XR1 105 
J 0
(-8475 2800);
DISPLAY 0.638298 (-8475 2800);
PAINT MONO (-8475 2800);
FORCEPROP 2 LAST $XR0 104 
J 0
(-8355 2800);
DISPLAY 0.638298 (-8355 2800);
PAINT MONO (-8355 2800);
FORCEPROP 2 LAST PATH I179
J 0
(-8375 2850);
DISPLAY 1.021277 (-8375 2850);
DISPLAY INVISIBLE (-8375 2850);
FORCEPROP 1 LAST COMMENT_BODY TRUE
J 0
(-7975 2725);
DISPLAY 0.872340 (-7975 2725);
PAINT GREEN (-7975 2725);
DISPLAY INVISIBLE (-7975 2725);
FORCEPROP 1 LAST OFFPAGE TRUE
J 0
(-7750 2675);
DISPLAY 0.872340 (-7750 2675);
PAINT GREEN (-7750 2675);
DISPLAY INVISIBLE (-7750 2675);
FORCEPROP 2 LAST CDS_LIB mstr_standard
J 0
(-8075 2800);
DISPLAY 0.808511 (-8075 2800);
DISPLAY INVISIBLE (-8075 2800);
FORCEADD OFFPAGE..1
(-8075 4500);
FORCEPROP 2 LAST $XR0 43 
J 0
(-8296 4500);
DISPLAY 0.638298 (-8296 4500);
PAINT MONO (-8296 4500);
FORCEPROP 2 LAST PATH I18
J 0
(-8325 4550);
DISPLAY 1.021277 (-8325 4550);
DISPLAY INVISIBLE (-8325 4550);
FORCEPROP 1 LAST COMMENT_BODY TRUE
J 0
(-7950 4400);
DISPLAY 0.872340 (-7950 4400);
PAINT GREEN (-7950 4400);
DISPLAY INVISIBLE (-7950 4400);
FORCEPROP 1 LAST OFFPAGE TRUE
J 0
(-7750 4375);
DISPLAY 0.872340 (-7750 4375);
PAINT GREEN (-7750 4375);
DISPLAY INVISIBLE (-7750 4375);
FORCEPROP 2 LAST CDS_LIB mstr_standard
J 0
(-8075 4500);
DISPLAY 0.808511 (-8075 4500);
DISPLAY INVISIBLE (-8075 4500);
FORCEADD Q_CAP..1
R 2
(-8675 3200);
FORCEPROP 1 LAST LOCATION C160
J 2
(-8725 3300);
DISPLAY 0.489362 (-8725 3300);
PAINT SKYBLUE (-8725 3300);
FORCEPROP 0 LAST $SEC 1
J 0
(-8725 3350);
DISPLAY 0.680851 (-8725 3350);
PAINT MONO (-8725 3350);
DISPLAY INVISIBLE (-8725 3350);
FORCEPROP 0 LAST CDS_SEC 1
J 0
(-8725 3350);
DISPLAY 1.021277 (-8725 3350);
DISPLAY INVISIBLE (-8725 3350);
FORCEPROP 1 LASTPIN (-8675 3300) $PN 1
J 2
(-8685 3280);
DISPLAY 0.489362 (-8685 3280);
PAINT MONO (-8685 3280);
FORCEPROP 1 LASTPIN (-8675 3100) $PN 2
J 2
(-8685 3080);
DISPLAY 0.489362 (-8685 3080);
PAINT MONO (-8685 3080);
FORCEPROP 1 LAST MATERIAL X7R
J 2
(-8725 3100);
DISPLAY 0.489362 (-8725 3100);
PAINT SKYBLUE (-8725 3100);
FORCEPROP 1 LAST TOLERANCE 10%
J 2
(-8725 3150);
DISPLAY 0.489362 (-8725 3150);
PAINT SKYBLUE (-8725 3150);
FORCEPROP 1 LAST VALUE 0.1UF
J 2
(-8725 3250);
DISPLAY 0.489362 (-8725 3250);
PAINT SKYBLUE (-8725 3250);
FORCEPROP 1 LAST VOLTAGE 25V
J 2
(-8725 3200);
DISPLAY 0.489362 (-8725 3200);
PAINT SKYBLUE (-8725 3200);
FORCEPROP 1 LAST PACK_TYPE 0402
J 2
(-8725 3000);
DISPLAY 0.489362 (-8725 3000);
PAINT SKYBLUE (-8725 3000);
FORCEPROP 1 LAST PART_NUMBER CH4104K1B00
J 2
(-8725 3050);
DISPLAY 0.489362 (-8725 3050);
PAINT SKYBLUE (-8725 3050);
FORCEPROP 0 LAST BOM_COST MEM
J 2
(-8730 3345);
DISPLAY 0.595745 (-8730 3345);
PAINT MONO (-8730 3345);
DISPLAY INVISIBLE (-8730 3345);
FORCEPROP 2 LAST CDS_LIB pure_quanta
J 0
(-8675 3200);
DISPLAY INVISIBLE (-8675 3200);
FORCEPROP 1 LAST PATH I185
J 2
(-8725 3350);
DISPLAY 0.978723 (-8725 3350);
PAINT WHITE (-8725 3350);
DISPLAY INVISIBLE (-8725 3350);
FORCEPROP 0 LAST ROOM MEM_CH_A_CPU0_DIMM1
J 2
(-8730 3345);
DISPLAY 0.595745 (-8730 3345);
PAINT RED (-8730 3345);
DISPLAY INVISIBLE (-8730 3345);
FORCEADD GND..1
(-8675 2975);
FORCEPROP 3 LASTPIN (-8675 3025) SIG_NAME GND\g
J 0
(-8665 3035);
DISPLAY 0.659574 (-8665 3035);
PAINT MONO (-8665 3035);
DISPLAY INVISIBLE (-8665 3035);
FORCEPROP 2 LAST BOM_COST MEM
J 0
(-8650 3100);
DISPLAY 0.659574 (-8650 3100);
DISPLAY INVISIBLE (-8650 3100);
FORCEPROP 1 LAST SIZE 1B
J 0
(-8600 2925);
DISPLAY 0.723404 (-8600 2925);
PAINT GREEN (-8600 2925);
DISPLAY INVISIBLE (-8600 2925);
FORCEPROP 2 LAST CDS_LIB mstr_symbols
J 0
(-8675 2975);
DISPLAY 0.808511 (-8675 2975);
DISPLAY INVISIBLE (-8675 2975);
FORCEPROP 1 LAST BODY_TYPE PLUMBING
J 0
(-8720 2932);
DISPLAY 0.276596 (-8720 2932);
PAINT GREEN (-8720 2932);
DISPLAY INVISIBLE (-8720 2932);
FORCEPROP 1 LAST PATH I186
J 0
(-8600 2975);
DISPLAY 0.872340 (-8600 2975);
PAINT AQUA (-8600 2975);
DISPLAY INVISIBLE (-8600 2975);
FORCEPROP 1 LAST VOLTAGE 0
J 0
(-8695 3070);
DISPLAY 0.829787 (-8695 3070);
PAINT SKYBLUE (-8695 3070);
DISPLAY INVISIBLE (-8695 3070);
FORCEPROP 2 LAST ROOM MEM_EFGH_DECOUPLING_CAPS
J 0
(-8650 3050);
DISPLAY 0.659574 (-8650 3050);
PAINT RED (-8650 3050);
DISPLAY INVISIBLE (-8650 3050);
FORCEPROP 1 LAST HDL_POWER GND
J 0
(-8675 3125);
DISPLAY 0.723404 (-8675 3125);
PAINT GREEN (-8675 3125);
DISPLAY INVISIBLE (-8675 3125);
FORCEADD OFFPAGE..6
(-8950 2100);
FORCEPROP 2 LAST $XR5 81 
J 0
(-9350 2100);
DISPLAY 0.638298 (-9350 2100);
PAINT MONO (-9350 2100);
FORCEPROP 2 LAST $XR4 108 
J 0
(-9260 2172);
DISPLAY 0.638298 (-9260 2172);
PAINT MONO (-9260 2172);
FORCEPROP 2 LAST $XR3 107 
J 0
(-9260 2028);
DISPLAY 0.638298 (-9260 2028);
PAINT MONO (-9260 2028);
FORCEPROP 2 LAST $XR2 106 
J 0
(-9260 2136);
DISPLAY 0.638298 (-9260 2136);
PAINT MONO (-9260 2136);
FORCEPROP 2 LAST $XR1 105 
J 0
(-9260 2064);
DISPLAY 0.638298 (-9260 2064);
PAINT MONO (-9260 2064);
FORCEPROP 2 LAST $XR0 104 
J 0
(-9260 2100);
DISPLAY 0.638298 (-9260 2100);
PAINT MONO (-9260 2100);
FORCEPROP 2 LAST PATH I187
J 0
(-8900 2175);
DISPLAY 1.021277 (-8900 2175);
DISPLAY INVISIBLE (-8900 2175);
FORCEPROP 1 LAST COMMENT_BODY TRUE
J 0
(-8850 2025);
DISPLAY 0.872340 (-8850 2025);
PAINT GREEN (-8850 2025);
DISPLAY INVISIBLE (-8850 2025);
FORCEPROP 1 LAST OFFPAGE TRUE
J 0
(-8625 1975);
DISPLAY 0.872340 (-8625 1975);
PAINT GREEN (-8625 1975);
DISPLAY INVISIBLE (-8625 1975);
FORCEPROP 2 LAST CDS_LIB mstr_standard
J 0
(-8950 2100);
DISPLAY INVISIBLE (-8950 2100);
FORCEADD Q_RES..1
R 2
(-8400 2100);
FORCEPROP 1 LAST LOCATION R1184
J 2
(-8350 2150);
DISPLAY 0.489362 (-8350 2150);
PAINT SKYBLUE (-8350 2150);
FORCEPROP 0 LAST $SEC 1
J 0
(-8350 2200);
DISPLAY 0.680851 (-8350 2200);
PAINT MONO (-8350 2200);
DISPLAY INVISIBLE (-8350 2200);
FORCEPROP 0 LAST CDS_SEC 1
J 0
(-8350 2200);
DISPLAY 1.021277 (-8350 2200);
DISPLAY INVISIBLE (-8350 2200);
FORCEPROP 1 LASTPIN (-8300 2100) $PN 1
J 2
(-8312 2112);
DISPLAY 0.489362 (-8312 2112);
PAINT MONO (-8312 2112);
FORCEPROP 1 LASTPIN (-8500 2100) $PN 2
J 2
(-8462 2112);
DISPLAY 0.489362 (-8462 2112);
PAINT MONO (-8462 2112);
FORCEPROP 1 LAST VALUE 0
J 0
(-8400 2050);
DISPLAY 0.489362 (-8400 2050);
PAINT SKYBLUE (-8400 2050);
FORCEPROP 2 LAST CDS_LIB pure_quanta
J 0
(-8400 2100);
DISPLAY INVISIBLE (-8400 2100);
FORCEPROP 2 LAST BOM_COST MEM
J 0
(-8425 2250);
DISPLAY 0.744681 (-8425 2250);
PAINT WHITE (-8425 2250);
DISPLAY INVISIBLE (-8425 2250);
FORCEPROP 1 LAST PATH I188
J 2
(-8350 2250);
DISPLAY 0.978723 (-8350 2250);
PAINT WHITE (-8350 2250);
DISPLAY INVISIBLE (-8350 2250);
FORCEPROP 1 LAST WATTAGE 1/16W
J 0
(-8325 2025);
DISPLAY 0.489362 (-8325 2025);
PAINT SKYBLUE (-8325 2025);
DISPLAY INVISIBLE (-8325 2025);
FORCEPROP 1 LAST MATERIAL CHIP
J 0
(-8575 2075);
DISPLAY 0.489362 (-8575 2075);
PAINT SKYBLUE (-8575 2075);
DISPLAY INVISIBLE (-8575 2075);
FORCEPROP 1 LAST TOLERANCE 5%
J 2
(-8275 2075);
DISPLAY 0.489362 (-8275 2075);
PAINT SKYBLUE (-8275 2075);
DISPLAY INVISIBLE (-8275 2075);
FORCEPROP 1 LAST PART_NUMBER CS00002JB38
J 0
(-8500 2150);
DISPLAY 0.489362 (-8500 2150);
PAINT SKYBLUE (-8500 2150);
DISPLAY INVISIBLE (-8500 2150);
FORCEPROP 1 LAST PACK_TYPE 0402LF
J 0
(-8575 2025);
DISPLAY 0.489362 (-8575 2025);
PAINT SKYBLUE (-8575 2025);
DISPLAY INVISIBLE (-8575 2025);
FORCEPROP 2 LAST ROOM RST_CPU0_PLD_TO_DIMM
J 0
(-8425 2200);
DISPLAY 0.744681 (-8425 2200);
PAINT RED (-8425 2200);
DISPLAY INVISIBLE (-8425 2200);
FORCEADD Q_RES..2
R 2
(-8525 2250);
FORCEPROP 1 LAST LOCATION R109
J 2
(-8570 2375);
DISPLAY 0.489362 (-8570 2375);
PAINT SKYBLUE (-8570 2375);
FORCEPROP 0 LAST $SEC 1
J 0
(-8550 2425);
DISPLAY 0.680851 (-8550 2425);
PAINT MONO (-8550 2425);
DISPLAY INVISIBLE (-8550 2425);
FORCEPROP 0 LAST CDS_SEC 1
J 0
(-8550 2425);
DISPLAY 1.021277 (-8550 2425);
DISPLAY INVISIBLE (-8550 2425);
FORCEPROP 1 LASTPIN (-8525 2350) $PN 1
J 2
(-8530 2312);
DISPLAY 0.489362 (-8530 2312);
PAINT MONO (-8530 2312);
FORCEPROP 1 LASTPIN (-8525 2150) $PN 2
J 2
(-8530 2160);
DISPLAY 0.489362 (-8530 2160);
PAINT MONO (-8530 2160);
FORCEPROP 1 LAST MATERIAL CHIP
J 2
(-8575 2250);
DISPLAY 0.489362 (-8575 2250);
PAINT SKYBLUE (-8575 2250);
FORCEPROP 1 LAST TOLERANCE 5%
J 2
(-8575 2300);
DISPLAY 0.489362 (-8575 2300);
PAINT SKYBLUE (-8575 2300);
FORCEPROP 1 LAST VALUE 1K
J 2
(-8570 2325);
DISPLAY 0.489362 (-8570 2325);
PAINT SKYBLUE (-8570 2325);
FORCEPROP 1 LAST PART_NUMBER TMP_QCS21002JB34
J 2
(-8575 2225);
DISPLAY 0.489362 (-8575 2225);
PAINT SKYBLUE (-8575 2225);
FORCEPROP 1 LAST PACK_TYPE 0402LF
J 2
(-8575 2200);
DISPLAY 0.489362 (-8575 2200);
PAINT SKYBLUE (-8575 2200);
FORCEPROP 1 LAST WATTAGE 1/16W
J 2
(-8575 2275);
DISPLAY 0.489362 (-8575 2275);
PAINT SKYBLUE (-8575 2275);
FORCEPROP 2 LAST BOM_COST MEM
J 2
(-8575 2425);
DISPLAY 0.808511 (-8575 2425);
DISPLAY INVISIBLE (-8575 2425);
FORCEPROP 2 LAST CDS_LIB pure_quanta
J 2
(-8525 2250);
DISPLAY INVISIBLE (-8525 2250);
FORCEPROP 1 LAST PATH I189
J 2
(-8575 2425);
DISPLAY 0.978723 (-8575 2425);
PAINT WHITE (-8575 2425);
DISPLAY INVISIBLE (-8575 2425);
FORCEPROP 2 LAST ROOM MEM_CH_A_CPU0_DIMM1
J 2
(-8575 2475);
DISPLAY 0.808511 (-8575 2475);
PAINT RED (-8575 2475);
DISPLAY INVISIBLE (-8575 2475);
FORCEADD OFFPAGE..1
(-8075 4550);
FORCEPROP 2 LAST $XR0 43 
J 0
(-8296 4550);
DISPLAY 0.638298 (-8296 4550);
PAINT MONO (-8296 4550);
FORCEPROP 2 LAST PATH I19
J 0
(-8325 4600);
DISPLAY 1.021277 (-8325 4600);
DISPLAY INVISIBLE (-8325 4600);
FORCEPROP 1 LAST COMMENT_BODY TRUE
J 0
(-7950 4450);
DISPLAY 0.872340 (-7950 4450);
PAINT GREEN (-7950 4450);
DISPLAY INVISIBLE (-7950 4450);
FORCEPROP 1 LAST OFFPAGE TRUE
J 0
(-7750 4425);
DISPLAY 0.872340 (-7750 4425);
PAINT GREEN (-7750 4425);
DISPLAY INVISIBLE (-7750 4425);
FORCEPROP 2 LAST CDS_LIB mstr_standard
J 0
(-8075 4550);
DISPLAY 0.723404 (-8075 4550);
PAINT MONO (-8075 4550);
DISPLAY INVISIBLE (-8075 4550);
FORCEADD VCC_CORE..1
(-8525 2425);
FORCEPROP 3 LASTPIN (-8525 2375) SIG_NAME P3V3_STBY\g
J 0
(-8515 2385);
DISPLAY 0.659574 (-8515 2385);
PAINT MONO (-8515 2385);
DISPLAY INVISIBLE (-8515 2385);
FORCEPROP 1 LAST HDL_POWER P3V3_STBY
J 1
(-8525 2475);
DISPLAY 0.489362 (-8525 2475);
PAINT GREEN (-8525 2475);
FORCEPROP 2 LAST CDS_LIB mstr_symbols
J 0
(-8525 2425);
DISPLAY INVISIBLE (-8525 2425);
FORCEPROP 1 LAST PATH I190
J 0
(-8475 2450);
DISPLAY 0.872340 (-8475 2450);
PAINT AQUA (-8475 2450);
DISPLAY INVISIBLE (-8475 2450);
FORCEPROP 0 LAST VOLTAGE 3.3
J 0
(-8800 2575);
DISPLAY 1.021277 (-8800 2575);
PAINT SKYBLUE (-8800 2575);
DISPLAY INVISIBLE (-8800 2575);
FORCEPROP 2 LAST ROOM PVCCINFAON_CPU0_CTRL
J 0
(-8525 2525);
DISPLAY 0.808511 (-8525 2525);
PAINT RED (-8525 2525);
DISPLAY INVISIBLE (-8525 2525);
FORCEADD VCC_CORE..1
(-8275 2425);
FORCEPROP 3 LASTPIN (-8275 2375) SIG_NAME P3V3_STBY\g
J 0
(-8265 2385);
DISPLAY 0.659574 (-8265 2385);
PAINT MONO (-8265 2385);
DISPLAY INVISIBLE (-8265 2385);
FORCEPROP 1 LAST HDL_POWER P3V3_STBY
J 1
(-8275 2475);
DISPLAY 0.489362 (-8275 2475);
PAINT GREEN (-8275 2475);
FORCEPROP 2 LAST CDS_LIB mstr_symbols
J 0
(-8275 2425);
DISPLAY INVISIBLE (-8275 2425);
FORCEPROP 1 LAST PATH I191
J 0
(-8225 2450);
DISPLAY 0.872340 (-8225 2450);
PAINT AQUA (-8225 2450);
DISPLAY INVISIBLE (-8225 2450);
FORCEPROP 0 LAST VOLTAGE 3.3
J 0
(-8550 2575);
DISPLAY 1.021277 (-8550 2575);
PAINT SKYBLUE (-8550 2575);
DISPLAY INVISIBLE (-8550 2575);
FORCEPROP 2 LAST ROOM PVCCINFAON_CPU0_CTRL
J 0
(-8275 2525);
DISPLAY 0.808511 (-8275 2525);
PAINT RED (-8275 2525);
DISPLAY INVISIBLE (-8275 2525);
FORCEADD Q_RES..2
(-8275 2250);
FORCEPROP 1 LAST LOCATION R110
J 0
(-8230 2375);
DISPLAY 0.489362 (-8230 2375);
PAINT SKYBLUE (-8230 2375);
FORCEPROP 0 LAST $SEC 1
J 0
(-8225 2425);
DISPLAY 0.680851 (-8225 2425);
PAINT MONO (-8225 2425);
DISPLAY INVISIBLE (-8225 2425);
FORCEPROP 0 LAST CDS_SEC 1
J 0
(-8225 2425);
DISPLAY 1.021277 (-8225 2425);
DISPLAY INVISIBLE (-8225 2425);
FORCEPROP 1 LASTPIN (-8275 2350) $PN 1
J 0
(-8270 2312);
DISPLAY 0.489362 (-8270 2312);
PAINT MONO (-8270 2312);
FORCEPROP 1 LASTPIN (-8275 2150) $PN 2
J 0
(-8270 2160);
DISPLAY 0.489362 (-8270 2160);
PAINT MONO (-8270 2160);
FORCEPROP 1 LAST WATTAGE 1/16W
J 0
(-8225 2275);
DISPLAY 0.489362 (-8225 2275);
PAINT SKYBLUE (-8225 2275);
FORCEPROP 1 LAST MATERIAL EMPTY
J 0
(-8225 2250);
DISPLAY 0.489362 (-8225 2250);
PAINT RED (-8225 2250);
FORCEPROP 1 LAST TOLERANCE 5%
J 0
(-8225 2300);
DISPLAY 0.489362 (-8225 2300);
PAINT SKYBLUE (-8225 2300);
FORCEPROP 1 LAST VALUE 1K
J 0
(-8230 2325);
DISPLAY 0.489362 (-8230 2325);
PAINT SKYBLUE (-8230 2325);
FORCEPROP 1 LAST PACK_TYPE 0402LF
J 0
(-8225 2200);
DISPLAY 0.489362 (-8225 2200);
PAINT SKYBLUE (-8225 2200);
FORCEPROP 2 LAST CDS_LIB pure_quanta
J 0
(-8275 2250);
DISPLAY INVISIBLE (-8275 2250);
FORCEPROP 2 LAST BOM_COST MEM
J 0
(-8225 2425);
DISPLAY 0.808511 (-8225 2425);
DISPLAY INVISIBLE (-8225 2425);
FORCEPROP 1 LAST PATH I192
J 0
(-8225 2425);
DISPLAY 0.978723 (-8225 2425);
PAINT WHITE (-8225 2425);
DISPLAY INVISIBLE (-8225 2425);
FORCEPROP 1 LAST PART_NUMBER TMP_QCS21002JB34
J 0
(-8225 2225);
DISPLAY 0.489362 (-8225 2225);
PAINT SKYBLUE (-8225 2225);
DISPLAY INVISIBLE (-8225 2225);
FORCEPROP 2 LAST ROOM MEM_CH_A_CPU0_DIMM1
J 0
(-8225 2475);
DISPLAY 0.808511 (-8225 2475);
PAINT RED (-8225 2475);
DISPLAY INVISIBLE (-8225 2475);
FORCEADD OFFPAGE..2
(-2450 4425);
FORCEPROP 2 LAST $XR0 43 
J 0
(-2261 4425);
DISPLAY 0.638298 (-2261 4425);
PAINT MONO (-2261 4425);
FORCEPROP 1 LAST COMMENT_BODY TRUE
J 0
(-2495 4330);
DISPLAY 0.872340 (-2495 4330);
PAINT GREEN (-2495 4330);
DISPLAY INVISIBLE (-2495 4330);
FORCEPROP 1 LAST OFFPAGE TRUE
J 0
(-2125 4300);
DISPLAY 0.723404 (-2125 4300);
PAINT GREEN (-2125 4300);
DISPLAY INVISIBLE (-2125 4300);
FORCEPROP 2 LAST CDS_LIB mstr_standard
J 0
(-2450 4425);
DISPLAY 0.723404 (-2450 4425);
PAINT MONO (-2450 4425);
DISPLAY INVISIBLE (-2450 4425);
FORCEPROP 2 LAST PATH I194
J 0
(-2250 4475);
DISPLAY 0.680851 (-2250 4475);
DISPLAY INVISIBLE (-2250 4475);
FORCEADD OFFPAGE..2
(-2450 4475);
FORCEPROP 2 LAST $XR0 43 
J 0
(-2261 4475);
DISPLAY 0.638298 (-2261 4475);
PAINT MONO (-2261 4475);
FORCEPROP 1 LAST COMMENT_BODY TRUE
J 0
(-2495 4380);
DISPLAY 0.872340 (-2495 4380);
PAINT GREEN (-2495 4380);
DISPLAY INVISIBLE (-2495 4380);
FORCEPROP 1 LAST OFFPAGE TRUE
J 0
(-2125 4350);
DISPLAY 0.723404 (-2125 4350);
PAINT GREEN (-2125 4350);
DISPLAY INVISIBLE (-2125 4350);
FORCEPROP 2 LAST CDS_LIB mstr_standard
J 0
(-2450 4475);
DISPLAY 0.723404 (-2450 4475);
PAINT MONO (-2450 4475);
DISPLAY INVISIBLE (-2450 4475);
FORCEPROP 2 LAST PATH I195
J 0
(-2250 4525);
DISPLAY 0.680851 (-2250 4525);
DISPLAY INVISIBLE (-2250 4525);
FORCEADD OFFPAGE..2
(-2450 3375);
FORCEPROP 2 LAST $XR0 43 
J 0
(-2261 3375);
DISPLAY 0.638298 (-2261 3375);
PAINT MONO (-2261 3375);
FORCEPROP 1 LAST COMMENT_BODY TRUE
J 0
(-2495 3280);
DISPLAY 0.872340 (-2495 3280);
PAINT GREEN (-2495 3280);
DISPLAY INVISIBLE (-2495 3280);
FORCEPROP 1 LAST OFFPAGE TRUE
J 0
(-2125 3250);
DISPLAY 0.723404 (-2125 3250);
PAINT GREEN (-2125 3250);
DISPLAY INVISIBLE (-2125 3250);
FORCEPROP 2 LAST CDS_LIB mstr_standard
J 0
(-2450 3375);
DISPLAY 0.723404 (-2450 3375);
PAINT MONO (-2450 3375);
DISPLAY INVISIBLE (-2450 3375);
FORCEPROP 2 LAST PATH I196
J 0
(-2250 3425);
DISPLAY 0.680851 (-2250 3425);
DISPLAY INVISIBLE (-2250 3425);
FORCEADD OFFPAGE..2
(-2450 3425);
FORCEPROP 2 LAST $XR0 43 
J 0
(-2261 3425);
DISPLAY 0.638298 (-2261 3425);
PAINT MONO (-2261 3425);
FORCEPROP 1 LAST COMMENT_BODY TRUE
J 0
(-2495 3330);
DISPLAY 0.872340 (-2495 3330);
PAINT GREEN (-2495 3330);
DISPLAY INVISIBLE (-2495 3330);
FORCEPROP 1 LAST OFFPAGE TRUE
J 0
(-2125 3300);
DISPLAY 0.723404 (-2125 3300);
PAINT GREEN (-2125 3300);
DISPLAY INVISIBLE (-2125 3300);
FORCEPROP 2 LAST CDS_LIB mstr_standard
J 0
(-2450 3425);
DISPLAY 0.723404 (-2450 3425);
PAINT MONO (-2450 3425);
DISPLAY INVISIBLE (-2450 3425);
FORCEPROP 2 LAST PATH I197
J 0
(-2250 3475);
DISPLAY 0.680851 (-2250 3475);
DISPLAY INVISIBLE (-2250 3475);
FORCEADD TAP..1
(-3050 4375);
FORCEPROP 3 LASTPIN (-3100 4375) SIG_NAME M_G_CPU1_SA_DQS_DN<9>
J 0
(-3090 4385);
DISPLAY 0.659574 (-3090 4385);
PAINT MONO (-3090 4385);
DISPLAY INVISIBLE (-3090 4385);
FORCEPROP 1 LASTPIN (-3100 4375) BN 9
J 0
(-3112 4383);
DISPLAY 0.489362 (-3112 4383);
PAINT GREEN (-3112 4383);
FORCEPROP 2 LAST CDS_LIB mstr_standard
J 0
(-3050 4375);
DISPLAY 0.723404 (-3050 4375);
PAINT MONO (-3050 4375);
DISPLAY INVISIBLE (-3050 4375);
FORCEPROP 1 LAST BODY_TYPE PLUMBING
J 0
(-3050 4425);
DISPLAY 0.872340 (-3050 4425);
PAINT GREEN (-3050 4425);
DISPLAY INVISIBLE (-3050 4425);
FORCEPROP 1 LAST HDL_TAP TRUE
J 0
(-2725 4250);
DISPLAY 0.872340 (-2725 4250);
DISPLAY INVISIBLE (-2725 4250);
FORCEPROP 1 LAST PATH I198
J 0
(-3052 4375);
DISPLAY 0.872340 (-3052 4375);
PAINT GREEN (-3052 4375);
DISPLAY INVISIBLE (-3052 4375);
FORCEADD TAP..1
(-3050 4275);
FORCEPROP 3 LASTPIN (-3100 4275) SIG_NAME M_G_CPU1_SA_DQS_DN<8>
J 0
(-3090 4285);
DISPLAY 0.659574 (-3090 4285);
PAINT MONO (-3090 4285);
DISPLAY INVISIBLE (-3090 4285);
FORCEPROP 1 LASTPIN (-3100 4275) BN 8
J 0
(-3112 4283);
DISPLAY 0.489362 (-3112 4283);
PAINT GREEN (-3112 4283);
FORCEPROP 2 LAST CDS_LIB mstr_standard
J 0
(-3050 4275);
DISPLAY 0.723404 (-3050 4275);
PAINT MONO (-3050 4275);
DISPLAY INVISIBLE (-3050 4275);
FORCEPROP 1 LAST BODY_TYPE PLUMBING
J 0
(-3050 4325);
DISPLAY 0.872340 (-3050 4325);
PAINT GREEN (-3050 4325);
DISPLAY INVISIBLE (-3050 4325);
FORCEPROP 1 LAST HDL_TAP TRUE
J 0
(-2725 4150);
DISPLAY 0.872340 (-2725 4150);
DISPLAY INVISIBLE (-2725 4150);
FORCEPROP 1 LAST PATH I199
J 0
(-3052 4275);
DISPLAY 0.872340 (-3052 4275);
PAINT GREEN (-3052 4275);
DISPLAY INVISIBLE (-3052 4275);
FORCEADD OFFPAGE..5
(-8075 1900);
FORCEPROP 2 LAST $XR0 43 
J 0
(-8329 1900);
DISPLAY 0.638298 (-8329 1900);
PAINT MONO (-8329 1900);
FORCEPROP 2 LAST PATH I2
J 0
(-8325 1950);
DISPLAY 1.021277 (-8325 1950);
DISPLAY INVISIBLE (-8325 1950);
FORCEPROP 1 LAST COMMENT_BODY TRUE
J 0
(-7975 1825);
DISPLAY 0.872340 (-7975 1825);
PAINT GREEN (-7975 1825);
DISPLAY INVISIBLE (-7975 1825);
FORCEPROP 1 LAST OFFPAGE TRUE
J 0
(-7750 1775);
DISPLAY 0.872340 (-7750 1775);
PAINT GREEN (-7750 1775);
DISPLAY INVISIBLE (-7750 1775);
FORCEPROP 2 LAST CDS_LIB mstr_standard
J 0
(-8075 1900);
DISPLAY 0.808511 (-8075 1900);
DISPLAY INVISIBLE (-8075 1900);
FORCEADD OFFPAGE..1
(-8075 5000);
FORCEPROP 2 LAST $XR0 43 
J 0
(-8296 5000);
DISPLAY 0.638298 (-8296 5000);
PAINT MONO (-8296 5000);
FORCEPROP 2 LAST PATH I20
J 0
(-8325 5050);
DISPLAY 1.021277 (-8325 5050);
DISPLAY INVISIBLE (-8325 5050);
FORCEPROP 1 LAST COMMENT_BODY TRUE
J 0
(-7950 4900);
DISPLAY 0.872340 (-7950 4900);
PAINT GREEN (-7950 4900);
DISPLAY INVISIBLE (-7950 4900);
FORCEPROP 1 LAST OFFPAGE TRUE
J 0
(-7750 4875);
DISPLAY 0.872340 (-7750 4875);
PAINT GREEN (-7750 4875);
DISPLAY INVISIBLE (-7750 4875);
FORCEPROP 2 LAST CDS_LIB mstr_standard
J 0
(-8075 5000);
DISPLAY 0.723404 (-8075 5000);
PAINT MONO (-8075 5000);
DISPLAY INVISIBLE (-8075 5000);
FORCEADD TAP..1
(-3250 4425);
FORCEPROP 3 LASTPIN (-3300 4425) SIG_NAME M_G_CPU1_SA_DQS_DP<9>
J 0
(-3290 4435);
DISPLAY 0.659574 (-3290 4435);
PAINT MONO (-3290 4435);
DISPLAY INVISIBLE (-3290 4435);
FORCEPROP 1 LASTPIN (-3300 4425) BN 9
J 0
(-3312 4433);
DISPLAY 0.489362 (-3312 4433);
PAINT GREEN (-3312 4433);
FORCEPROP 2 LAST CDS_LIB mstr_standard
J 0
(-3250 4425);
DISPLAY 0.723404 (-3250 4425);
PAINT MONO (-3250 4425);
DISPLAY INVISIBLE (-3250 4425);
FORCEPROP 1 LAST BODY_TYPE PLUMBING
J 0
(-3250 4475);
DISPLAY 0.872340 (-3250 4475);
PAINT GREEN (-3250 4475);
DISPLAY INVISIBLE (-3250 4475);
FORCEPROP 1 LAST HDL_TAP TRUE
J 0
(-2925 4300);
DISPLAY 0.872340 (-2925 4300);
DISPLAY INVISIBLE (-2925 4300);
FORCEPROP 1 LAST PATH I200
J 0
(-3252 4425);
DISPLAY 0.872340 (-3252 4425);
PAINT GREEN (-3252 4425);
DISPLAY INVISIBLE (-3252 4425);
FORCEADD TAP..1
(-3250 4325);
FORCEPROP 3 LASTPIN (-3300 4325) SIG_NAME M_G_CPU1_SA_DQS_DP<8>
J 0
(-3290 4335);
DISPLAY 0.659574 (-3290 4335);
PAINT MONO (-3290 4335);
DISPLAY INVISIBLE (-3290 4335);
FORCEPROP 1 LASTPIN (-3300 4325) BN 8
J 0
(-3312 4333);
DISPLAY 0.489362 (-3312 4333);
PAINT GREEN (-3312 4333);
FORCEPROP 2 LAST CDS_LIB mstr_standard
J 0
(-3250 4325);
DISPLAY 0.723404 (-3250 4325);
PAINT MONO (-3250 4325);
DISPLAY INVISIBLE (-3250 4325);
FORCEPROP 1 LAST BODY_TYPE PLUMBING
J 0
(-3250 4375);
DISPLAY 0.872340 (-3250 4375);
PAINT GREEN (-3250 4375);
DISPLAY INVISIBLE (-3250 4375);
FORCEPROP 1 LAST HDL_TAP TRUE
J 0
(-2925 4200);
DISPLAY 0.872340 (-2925 4200);
DISPLAY INVISIBLE (-2925 4200);
FORCEPROP 1 LAST PATH I201
J 0
(-3252 4325);
DISPLAY 0.872340 (-3252 4325);
PAINT GREEN (-3252 4325);
DISPLAY INVISIBLE (-3252 4325);
FORCEADD TAP..1
(-3050 4175);
FORCEPROP 3 LASTPIN (-3100 4175) SIG_NAME M_G_CPU1_SA_DQS_DN<7>
J 0
(-3090 4185);
DISPLAY 0.659574 (-3090 4185);
PAINT MONO (-3090 4185);
DISPLAY INVISIBLE (-3090 4185);
FORCEPROP 1 LASTPIN (-3100 4175) BN 7
J 0
(-3112 4183);
DISPLAY 0.489362 (-3112 4183);
PAINT GREEN (-3112 4183);
FORCEPROP 2 LAST CDS_LIB mstr_standard
J 0
(-3050 4175);
DISPLAY 0.723404 (-3050 4175);
PAINT MONO (-3050 4175);
DISPLAY INVISIBLE (-3050 4175);
FORCEPROP 1 LAST BODY_TYPE PLUMBING
J 0
(-3050 4225);
DISPLAY 0.872340 (-3050 4225);
PAINT GREEN (-3050 4225);
DISPLAY INVISIBLE (-3050 4225);
FORCEPROP 1 LAST HDL_TAP TRUE
J 0
(-2725 4050);
DISPLAY 0.872340 (-2725 4050);
DISPLAY INVISIBLE (-2725 4050);
FORCEPROP 1 LAST PATH I202
J 0
(-3052 4175);
DISPLAY 0.872340 (-3052 4175);
PAINT GREEN (-3052 4175);
DISPLAY INVISIBLE (-3052 4175);
FORCEADD TAP..1
(-3050 4075);
FORCEPROP 3 LASTPIN (-3100 4075) SIG_NAME M_G_CPU1_SA_DQS_DN<6>
J 0
(-3090 4085);
DISPLAY 0.659574 (-3090 4085);
PAINT MONO (-3090 4085);
DISPLAY INVISIBLE (-3090 4085);
FORCEPROP 1 LASTPIN (-3100 4075) BN 6
J 0
(-3112 4083);
DISPLAY 0.489362 (-3112 4083);
PAINT GREEN (-3112 4083);
FORCEPROP 2 LAST CDS_LIB mstr_standard
J 0
(-3050 4075);
DISPLAY 0.723404 (-3050 4075);
PAINT MONO (-3050 4075);
DISPLAY INVISIBLE (-3050 4075);
FORCEPROP 1 LAST BODY_TYPE PLUMBING
J 0
(-3050 4125);
DISPLAY 0.872340 (-3050 4125);
PAINT GREEN (-3050 4125);
DISPLAY INVISIBLE (-3050 4125);
FORCEPROP 1 LAST HDL_TAP TRUE
J 0
(-2725 3950);
DISPLAY 0.872340 (-2725 3950);
DISPLAY INVISIBLE (-2725 3950);
FORCEPROP 1 LAST PATH I203
J 0
(-3052 4075);
DISPLAY 0.872340 (-3052 4075);
PAINT GREEN (-3052 4075);
DISPLAY INVISIBLE (-3052 4075);
FORCEADD TAP..1
(-3050 3875);
FORCEPROP 3 LASTPIN (-3100 3875) SIG_NAME M_G_CPU1_SA_DQS_DN<4>
J 0
(-3090 3885);
DISPLAY 0.659574 (-3090 3885);
PAINT MONO (-3090 3885);
DISPLAY INVISIBLE (-3090 3885);
FORCEPROP 1 LASTPIN (-3100 3875) BN 4
J 0
(-3112 3883);
DISPLAY 0.489362 (-3112 3883);
PAINT GREEN (-3112 3883);
FORCEPROP 2 LAST CDS_LIB mstr_standard
J 0
(-3050 3875);
DISPLAY 0.723404 (-3050 3875);
PAINT MONO (-3050 3875);
DISPLAY INVISIBLE (-3050 3875);
FORCEPROP 1 LAST BODY_TYPE PLUMBING
J 0
(-3050 3925);
DISPLAY 0.872340 (-3050 3925);
PAINT GREEN (-3050 3925);
DISPLAY INVISIBLE (-3050 3925);
FORCEPROP 1 LAST HDL_TAP TRUE
J 0
(-2725 3750);
DISPLAY 0.872340 (-2725 3750);
DISPLAY INVISIBLE (-2725 3750);
FORCEPROP 1 LAST PATH I204
J 0
(-3052 3875);
DISPLAY 0.872340 (-3052 3875);
PAINT GREEN (-3052 3875);
DISPLAY INVISIBLE (-3052 3875);
FORCEADD TAP..1
(-3050 3975);
FORCEPROP 3 LASTPIN (-3100 3975) SIG_NAME M_G_CPU1_SA_DQS_DN<5>
J 0
(-3090 3985);
DISPLAY 0.659574 (-3090 3985);
PAINT MONO (-3090 3985);
DISPLAY INVISIBLE (-3090 3985);
FORCEPROP 1 LASTPIN (-3100 3975) BN 5
J 0
(-3112 3983);
DISPLAY 0.489362 (-3112 3983);
PAINT GREEN (-3112 3983);
FORCEPROP 2 LAST CDS_LIB mstr_standard
J 0
(-3050 3975);
DISPLAY 0.723404 (-3050 3975);
PAINT MONO (-3050 3975);
DISPLAY INVISIBLE (-3050 3975);
FORCEPROP 1 LAST BODY_TYPE PLUMBING
J 0
(-3050 4025);
DISPLAY 0.872340 (-3050 4025);
PAINT GREEN (-3050 4025);
DISPLAY INVISIBLE (-3050 4025);
FORCEPROP 1 LAST HDL_TAP TRUE
J 0
(-2725 3850);
DISPLAY 0.872340 (-2725 3850);
DISPLAY INVISIBLE (-2725 3850);
FORCEPROP 1 LAST PATH I205
J 0
(-3052 3975);
DISPLAY 0.872340 (-3052 3975);
PAINT GREEN (-3052 3975);
DISPLAY INVISIBLE (-3052 3975);
FORCEADD TAP..1
(-3050 3775);
FORCEPROP 3 LASTPIN (-3100 3775) SIG_NAME M_G_CPU1_SA_DQS_DN<3>
J 0
(-3090 3785);
DISPLAY 0.659574 (-3090 3785);
PAINT MONO (-3090 3785);
DISPLAY INVISIBLE (-3090 3785);
FORCEPROP 1 LASTPIN (-3100 3775) BN 3
J 0
(-3112 3783);
DISPLAY 0.489362 (-3112 3783);
PAINT GREEN (-3112 3783);
FORCEPROP 2 LAST CDS_LIB mstr_standard
J 0
(-3050 3775);
DISPLAY 0.723404 (-3050 3775);
PAINT MONO (-3050 3775);
DISPLAY INVISIBLE (-3050 3775);
FORCEPROP 1 LAST BODY_TYPE PLUMBING
J 0
(-3050 3825);
DISPLAY 0.872340 (-3050 3825);
PAINT GREEN (-3050 3825);
DISPLAY INVISIBLE (-3050 3825);
FORCEPROP 1 LAST HDL_TAP TRUE
J 0
(-2725 3650);
DISPLAY 0.872340 (-2725 3650);
DISPLAY INVISIBLE (-2725 3650);
FORCEPROP 1 LAST PATH I206
J 0
(-3052 3775);
DISPLAY 0.872340 (-3052 3775);
PAINT GREEN (-3052 3775);
DISPLAY INVISIBLE (-3052 3775);
FORCEADD TAP..1
(-3250 4225);
FORCEPROP 3 LASTPIN (-3300 4225) SIG_NAME M_G_CPU1_SA_DQS_DP<7>
J 0
(-3290 4235);
DISPLAY 0.659574 (-3290 4235);
PAINT MONO (-3290 4235);
DISPLAY INVISIBLE (-3290 4235);
FORCEPROP 1 LASTPIN (-3300 4225) BN 7
J 0
(-3312 4233);
DISPLAY 0.489362 (-3312 4233);
PAINT GREEN (-3312 4233);
FORCEPROP 2 LAST CDS_LIB mstr_standard
J 0
(-3250 4225);
DISPLAY 0.723404 (-3250 4225);
PAINT MONO (-3250 4225);
DISPLAY INVISIBLE (-3250 4225);
FORCEPROP 1 LAST BODY_TYPE PLUMBING
J 0
(-3250 4275);
DISPLAY 0.872340 (-3250 4275);
PAINT GREEN (-3250 4275);
DISPLAY INVISIBLE (-3250 4275);
FORCEPROP 1 LAST HDL_TAP TRUE
J 0
(-2925 4100);
DISPLAY 0.872340 (-2925 4100);
DISPLAY INVISIBLE (-2925 4100);
FORCEPROP 1 LAST PATH I207
J 0
(-3252 4225);
DISPLAY 0.872340 (-3252 4225);
PAINT GREEN (-3252 4225);
DISPLAY INVISIBLE (-3252 4225);
FORCEADD TAP..1
(-3250 4125);
FORCEPROP 3 LASTPIN (-3300 4125) SIG_NAME M_G_CPU1_SA_DQS_DP<6>
J 0
(-3290 4135);
DISPLAY 0.659574 (-3290 4135);
PAINT MONO (-3290 4135);
DISPLAY INVISIBLE (-3290 4135);
FORCEPROP 1 LASTPIN (-3300 4125) BN 6
J 0
(-3312 4133);
DISPLAY 0.489362 (-3312 4133);
PAINT GREEN (-3312 4133);
FORCEPROP 2 LAST CDS_LIB mstr_standard
J 0
(-3250 4125);
DISPLAY 0.723404 (-3250 4125);
PAINT MONO (-3250 4125);
DISPLAY INVISIBLE (-3250 4125);
FORCEPROP 1 LAST BODY_TYPE PLUMBING
J 0
(-3250 4175);
DISPLAY 0.872340 (-3250 4175);
PAINT GREEN (-3250 4175);
DISPLAY INVISIBLE (-3250 4175);
FORCEPROP 1 LAST HDL_TAP TRUE
J 0
(-2925 4000);
DISPLAY 0.872340 (-2925 4000);
DISPLAY INVISIBLE (-2925 4000);
FORCEPROP 1 LAST PATH I208
J 0
(-3252 4125);
DISPLAY 0.872340 (-3252 4125);
PAINT GREEN (-3252 4125);
DISPLAY INVISIBLE (-3252 4125);
FORCEADD TAP..1
(-3250 4025);
FORCEPROP 3 LASTPIN (-3300 4025) SIG_NAME M_G_CPU1_SA_DQS_DP<5>
J 0
(-3290 4035);
DISPLAY 0.659574 (-3290 4035);
PAINT MONO (-3290 4035);
DISPLAY INVISIBLE (-3290 4035);
FORCEPROP 1 LASTPIN (-3300 4025) BN 5
J 0
(-3312 4033);
DISPLAY 0.489362 (-3312 4033);
PAINT GREEN (-3312 4033);
FORCEPROP 2 LAST CDS_LIB mstr_standard
J 0
(-3250 4025);
DISPLAY 0.723404 (-3250 4025);
PAINT MONO (-3250 4025);
DISPLAY INVISIBLE (-3250 4025);
FORCEPROP 1 LAST BODY_TYPE PLUMBING
J 0
(-3250 4075);
DISPLAY 0.872340 (-3250 4075);
PAINT GREEN (-3250 4075);
DISPLAY INVISIBLE (-3250 4075);
FORCEPROP 1 LAST HDL_TAP TRUE
J 0
(-2925 3900);
DISPLAY 0.872340 (-2925 3900);
DISPLAY INVISIBLE (-2925 3900);
FORCEPROP 1 LAST PATH I209
J 0
(-3252 4025);
DISPLAY 0.872340 (-3252 4025);
PAINT GREEN (-3252 4025);
DISPLAY INVISIBLE (-3252 4025);
FORCEADD OFFPAGE..1
(-8075 5400);
FORCEPROP 2 LAST $XR0 43 
J 0
(-8296 5400);
DISPLAY 0.638298 (-8296 5400);
PAINT MONO (-8296 5400);
FORCEPROP 2 LAST PATH I21
J 0
(-8325 5450);
DISPLAY 1.021277 (-8325 5450);
DISPLAY INVISIBLE (-8325 5450);
FORCEPROP 1 LAST COMMENT_BODY TRUE
J 0
(-7950 5300);
DISPLAY 0.872340 (-7950 5300);
PAINT GREEN (-7950 5300);
DISPLAY INVISIBLE (-7950 5300);
FORCEPROP 1 LAST OFFPAGE TRUE
J 0
(-7750 5275);
DISPLAY 0.872340 (-7750 5275);
PAINT GREEN (-7750 5275);
DISPLAY INVISIBLE (-7750 5275);
FORCEPROP 2 LAST CDS_LIB mstr_standard
J 0
(-8075 5400);
DISPLAY 0.723404 (-8075 5400);
PAINT MONO (-8075 5400);
DISPLAY INVISIBLE (-8075 5400);
FORCEADD TAP..1
(-3250 3925);
FORCEPROP 3 LASTPIN (-3300 3925) SIG_NAME M_G_CPU1_SA_DQS_DP<4>
J 0
(-3290 3935);
DISPLAY 0.659574 (-3290 3935);
PAINT MONO (-3290 3935);
DISPLAY INVISIBLE (-3290 3935);
FORCEPROP 1 LASTPIN (-3300 3925) BN 4
J 0
(-3312 3933);
DISPLAY 0.489362 (-3312 3933);
PAINT GREEN (-3312 3933);
FORCEPROP 2 LAST CDS_LIB mstr_standard
J 0
(-3250 3925);
DISPLAY 0.723404 (-3250 3925);
PAINT MONO (-3250 3925);
DISPLAY INVISIBLE (-3250 3925);
FORCEPROP 1 LAST BODY_TYPE PLUMBING
J 0
(-3250 3975);
DISPLAY 0.872340 (-3250 3975);
PAINT GREEN (-3250 3975);
DISPLAY INVISIBLE (-3250 3975);
FORCEPROP 1 LAST HDL_TAP TRUE
J 0
(-2925 3800);
DISPLAY 0.872340 (-2925 3800);
DISPLAY INVISIBLE (-2925 3800);
FORCEPROP 1 LAST PATH I210
J 0
(-3252 3925);
DISPLAY 0.872340 (-3252 3925);
PAINT GREEN (-3252 3925);
DISPLAY INVISIBLE (-3252 3925);
FORCEADD TAP..1
(-3250 3825);
FORCEPROP 3 LASTPIN (-3300 3825) SIG_NAME M_G_CPU1_SA_DQS_DP<3>
J 0
(-3290 3835);
DISPLAY 0.659574 (-3290 3835);
PAINT MONO (-3290 3835);
DISPLAY INVISIBLE (-3290 3835);
FORCEPROP 1 LASTPIN (-3300 3825) BN 3
J 0
(-3312 3833);
DISPLAY 0.489362 (-3312 3833);
PAINT GREEN (-3312 3833);
FORCEPROP 2 LAST CDS_LIB mstr_standard
J 0
(-3250 3825);
DISPLAY 0.723404 (-3250 3825);
PAINT MONO (-3250 3825);
DISPLAY INVISIBLE (-3250 3825);
FORCEPROP 1 LAST BODY_TYPE PLUMBING
J 0
(-3250 3875);
DISPLAY 0.872340 (-3250 3875);
PAINT GREEN (-3250 3875);
DISPLAY INVISIBLE (-3250 3875);
FORCEPROP 1 LAST HDL_TAP TRUE
J 0
(-2925 3700);
DISPLAY 0.872340 (-2925 3700);
DISPLAY INVISIBLE (-2925 3700);
FORCEPROP 1 LAST PATH I211
J 0
(-3252 3825);
DISPLAY 0.872340 (-3252 3825);
PAINT GREEN (-3252 3825);
DISPLAY INVISIBLE (-3252 3825);
FORCEADD TAP..1
(-3050 3675);
FORCEPROP 3 LASTPIN (-3100 3675) SIG_NAME M_G_CPU1_SA_DQS_DN<2>
J 0
(-3090 3685);
DISPLAY 0.659574 (-3090 3685);
PAINT MONO (-3090 3685);
DISPLAY INVISIBLE (-3090 3685);
FORCEPROP 1 LASTPIN (-3100 3675) BN 2
J 0
(-3112 3683);
DISPLAY 0.489362 (-3112 3683);
PAINT GREEN (-3112 3683);
FORCEPROP 2 LAST CDS_LIB mstr_standard
J 0
(-3050 3675);
DISPLAY 0.723404 (-3050 3675);
PAINT MONO (-3050 3675);
DISPLAY INVISIBLE (-3050 3675);
FORCEPROP 1 LAST BODY_TYPE PLUMBING
J 0
(-3050 3725);
DISPLAY 0.872340 (-3050 3725);
PAINT GREEN (-3050 3725);
DISPLAY INVISIBLE (-3050 3725);
FORCEPROP 1 LAST HDL_TAP TRUE
J 0
(-2725 3550);
DISPLAY 0.872340 (-2725 3550);
DISPLAY INVISIBLE (-2725 3550);
FORCEPROP 1 LAST PATH I212
J 0
(-3052 3675);
DISPLAY 0.872340 (-3052 3675);
PAINT GREEN (-3052 3675);
DISPLAY INVISIBLE (-3052 3675);
FORCEADD TAP..1
(-3050 3575);
FORCEPROP 3 LASTPIN (-3100 3575) SIG_NAME M_G_CPU1_SA_DQS_DN<1>
J 0
(-3090 3585);
DISPLAY 0.659574 (-3090 3585);
PAINT MONO (-3090 3585);
DISPLAY INVISIBLE (-3090 3585);
FORCEPROP 1 LASTPIN (-3100 3575) BN 1
J 0
(-3112 3583);
DISPLAY 0.489362 (-3112 3583);
PAINT GREEN (-3112 3583);
FORCEPROP 2 LAST CDS_LIB mstr_standard
J 0
(-3050 3575);
DISPLAY 0.723404 (-3050 3575);
PAINT MONO (-3050 3575);
DISPLAY INVISIBLE (-3050 3575);
FORCEPROP 1 LAST BODY_TYPE PLUMBING
J 0
(-3050 3625);
DISPLAY 0.872340 (-3050 3625);
PAINT GREEN (-3050 3625);
DISPLAY INVISIBLE (-3050 3625);
FORCEPROP 1 LAST HDL_TAP TRUE
J 0
(-2725 3450);
DISPLAY 0.872340 (-2725 3450);
DISPLAY INVISIBLE (-2725 3450);
FORCEPROP 1 LAST PATH I213
J 0
(-3052 3575);
DISPLAY 0.872340 (-3052 3575);
PAINT GREEN (-3052 3575);
DISPLAY INVISIBLE (-3052 3575);
FORCEADD TAP..1
(-3050 3475);
FORCEPROP 3 LASTPIN (-3100 3475) SIG_NAME M_G_CPU1_SA_DQS_DN<0>
J 0
(-3090 3485);
DISPLAY 0.659574 (-3090 3485);
PAINT MONO (-3090 3485);
DISPLAY INVISIBLE (-3090 3485);
FORCEPROP 1 LASTPIN (-3100 3475) BN 0
J 0
(-3112 3483);
DISPLAY 0.489362 (-3112 3483);
PAINT GREEN (-3112 3483);
FORCEPROP 2 LAST CDS_LIB mstr_standard
J 0
(-3050 3475);
DISPLAY 0.723404 (-3050 3475);
PAINT MONO (-3050 3475);
DISPLAY INVISIBLE (-3050 3475);
FORCEPROP 1 LAST BODY_TYPE PLUMBING
J 0
(-3050 3525);
DISPLAY 0.872340 (-3050 3525);
PAINT GREEN (-3050 3525);
DISPLAY INVISIBLE (-3050 3525);
FORCEPROP 1 LAST HDL_TAP TRUE
J 0
(-2725 3350);
DISPLAY 0.872340 (-2725 3350);
DISPLAY INVISIBLE (-2725 3350);
FORCEPROP 1 LAST PATH I214
J 0
(-3052 3475);
DISPLAY 0.872340 (-3052 3475);
PAINT GREEN (-3052 3475);
DISPLAY INVISIBLE (-3052 3475);
FORCEADD TAP..1
(-3050 3325);
FORCEPROP 3 LASTPIN (-3100 3325) SIG_NAME M_G_CPU1_SB_DQS_DN<9>
J 0
(-3090 3335);
DISPLAY 0.659574 (-3090 3335);
PAINT MONO (-3090 3335);
DISPLAY INVISIBLE (-3090 3335);
FORCEPROP 1 LASTPIN (-3100 3325) BN 9
J 0
(-3112 3333);
DISPLAY 0.489362 (-3112 3333);
PAINT GREEN (-3112 3333);
FORCEPROP 2 LAST CDS_LIB mstr_standard
J 0
(-3050 3325);
DISPLAY 0.723404 (-3050 3325);
PAINT MONO (-3050 3325);
DISPLAY INVISIBLE (-3050 3325);
FORCEPROP 1 LAST BODY_TYPE PLUMBING
J 0
(-3050 3375);
DISPLAY 0.872340 (-3050 3375);
PAINT GREEN (-3050 3375);
DISPLAY INVISIBLE (-3050 3375);
FORCEPROP 1 LAST HDL_TAP TRUE
J 0
(-2725 3200);
DISPLAY 0.872340 (-2725 3200);
DISPLAY INVISIBLE (-2725 3200);
FORCEPROP 1 LAST PATH I215
J 0
(-3052 3325);
DISPLAY 0.872340 (-3052 3325);
PAINT GREEN (-3052 3325);
DISPLAY INVISIBLE (-3052 3325);
FORCEADD TAP..1
(-3050 3225);
FORCEPROP 3 LASTPIN (-3100 3225) SIG_NAME M_G_CPU1_SB_DQS_DN<8>
J 0
(-3090 3235);
DISPLAY 0.659574 (-3090 3235);
PAINT MONO (-3090 3235);
DISPLAY INVISIBLE (-3090 3235);
FORCEPROP 1 LASTPIN (-3100 3225) BN 8
J 0
(-3112 3233);
DISPLAY 0.489362 (-3112 3233);
PAINT GREEN (-3112 3233);
FORCEPROP 2 LAST CDS_LIB mstr_standard
J 0
(-3050 3225);
DISPLAY 0.723404 (-3050 3225);
PAINT MONO (-3050 3225);
DISPLAY INVISIBLE (-3050 3225);
FORCEPROP 1 LAST BODY_TYPE PLUMBING
J 0
(-3050 3275);
DISPLAY 0.872340 (-3050 3275);
PAINT GREEN (-3050 3275);
DISPLAY INVISIBLE (-3050 3275);
FORCEPROP 1 LAST HDL_TAP TRUE
J 0
(-2725 3100);
DISPLAY 0.872340 (-2725 3100);
DISPLAY INVISIBLE (-2725 3100);
FORCEPROP 1 LAST PATH I216
J 0
(-3052 3225);
DISPLAY 0.872340 (-3052 3225);
PAINT GREEN (-3052 3225);
DISPLAY INVISIBLE (-3052 3225);
FORCEADD TAP..1
(-3250 3725);
FORCEPROP 3 LASTPIN (-3300 3725) SIG_NAME M_G_CPU1_SA_DQS_DP<2>
J 0
(-3290 3735);
DISPLAY 0.659574 (-3290 3735);
PAINT MONO (-3290 3735);
DISPLAY INVISIBLE (-3290 3735);
FORCEPROP 1 LASTPIN (-3300 3725) BN 2
J 0
(-3312 3733);
DISPLAY 0.489362 (-3312 3733);
PAINT GREEN (-3312 3733);
FORCEPROP 2 LAST CDS_LIB mstr_standard
J 0
(-3250 3725);
DISPLAY 0.723404 (-3250 3725);
PAINT MONO (-3250 3725);
DISPLAY INVISIBLE (-3250 3725);
FORCEPROP 1 LAST BODY_TYPE PLUMBING
J 0
(-3250 3775);
DISPLAY 0.872340 (-3250 3775);
PAINT GREEN (-3250 3775);
DISPLAY INVISIBLE (-3250 3775);
FORCEPROP 1 LAST HDL_TAP TRUE
J 0
(-2925 3600);
DISPLAY 0.872340 (-2925 3600);
DISPLAY INVISIBLE (-2925 3600);
FORCEPROP 1 LAST PATH I217
J 0
(-3252 3725);
DISPLAY 0.872340 (-3252 3725);
PAINT GREEN (-3252 3725);
DISPLAY INVISIBLE (-3252 3725);
FORCEADD TAP..1
(-3250 3625);
FORCEPROP 3 LASTPIN (-3300 3625) SIG_NAME M_G_CPU1_SA_DQS_DP<1>
J 0
(-3290 3635);
DISPLAY 0.659574 (-3290 3635);
PAINT MONO (-3290 3635);
DISPLAY INVISIBLE (-3290 3635);
FORCEPROP 1 LASTPIN (-3300 3625) BN 1
J 0
(-3312 3633);
DISPLAY 0.489362 (-3312 3633);
PAINT GREEN (-3312 3633);
FORCEPROP 2 LAST CDS_LIB mstr_standard
J 0
(-3250 3625);
DISPLAY 0.723404 (-3250 3625);
PAINT MONO (-3250 3625);
DISPLAY INVISIBLE (-3250 3625);
FORCEPROP 1 LAST BODY_TYPE PLUMBING
J 0
(-3250 3675);
DISPLAY 0.872340 (-3250 3675);
PAINT GREEN (-3250 3675);
DISPLAY INVISIBLE (-3250 3675);
FORCEPROP 1 LAST HDL_TAP TRUE
J 0
(-2925 3500);
DISPLAY 0.872340 (-2925 3500);
DISPLAY INVISIBLE (-2925 3500);
FORCEPROP 1 LAST PATH I218
J 0
(-3252 3625);
DISPLAY 0.872340 (-3252 3625);
PAINT GREEN (-3252 3625);
DISPLAY INVISIBLE (-3252 3625);
FORCEADD TAP..1
(-3250 3525);
FORCEPROP 3 LASTPIN (-3300 3525) SIG_NAME M_G_CPU1_SA_DQS_DP<0>
J 0
(-3290 3535);
DISPLAY 0.659574 (-3290 3535);
PAINT MONO (-3290 3535);
DISPLAY INVISIBLE (-3290 3535);
FORCEPROP 1 LASTPIN (-3300 3525) BN 0
J 0
(-3312 3533);
DISPLAY 0.489362 (-3312 3533);
PAINT GREEN (-3312 3533);
FORCEPROP 2 LAST CDS_LIB mstr_standard
J 0
(-3250 3525);
DISPLAY 0.723404 (-3250 3525);
PAINT MONO (-3250 3525);
DISPLAY INVISIBLE (-3250 3525);
FORCEPROP 1 LAST BODY_TYPE PLUMBING
J 0
(-3250 3575);
DISPLAY 0.872340 (-3250 3575);
PAINT GREEN (-3250 3575);
DISPLAY INVISIBLE (-3250 3575);
FORCEPROP 1 LAST HDL_TAP TRUE
J 0
(-2925 3400);
DISPLAY 0.872340 (-2925 3400);
DISPLAY INVISIBLE (-2925 3400);
FORCEPROP 1 LAST PATH I219
J 0
(-3252 3525);
DISPLAY 0.872340 (-3252 3525);
PAINT GREEN (-3252 3525);
DISPLAY INVISIBLE (-3252 3525);
FORCEADD SCONN288_DDR506112002KQ..1
(-6625 3600);
FORCEPROP 1 LAST LOCATION J102
J 0
(-7075 5675);
DISPLAY 0.468085 (-7075 5675);
PAINT SKYBLUE (-7075 5675);
FORCEPROP 0 LAST $SEC 1
J 0
(-7075 5825);
DISPLAY 0.680851 (-7075 5825);
PAINT MONO (-7075 5825);
DISPLAY INVISIBLE (-7075 5825);
FORCEPROP 0 LAST CDS_SEC 1
J 0
(-7075 5825);
DISPLAY 0.680851 (-7075 5825);
DISPLAY INVISIBLE (-7075 5825);
FORCEPROP 0 LASTPIN (-7225 3000) $PN 62
J 2
(-7235 3010);
DISPLAY 0.680851 (-7235 3010);
PAINT MONO (-7235 3010);
FORCEPROP 0 LASTPIN (-7225 5050) $PN 66
J 2
(-7235 5060);
DISPLAY 0.680851 (-7235 5060);
PAINT MONO (-7235 5060);
FORCEPROP 0 LASTPIN (-7225 4650) $PN 76
J 2
(-7235 4660);
DISPLAY 0.680851 (-7235 4660);
PAINT MONO (-7235 4660);
FORCEPROP 0 LASTPIN (-7225 5100) $PN 211
J 2
(-7235 5110);
DISPLAY 0.680851 (-7235 5110);
PAINT MONO (-7235 5110);
FORCEPROP 0 LASTPIN (-7225 4700) $PN 221
J 2
(-7235 4710);
DISPLAY 0.680851 (-7235 4710);
PAINT MONO (-7235 4710);
FORCEPROP 0 LASTPIN (-7225 5150) $PN 68
J 2
(-7235 5160);
DISPLAY 0.680851 (-7235 5160);
PAINT MONO (-7235 5160);
FORCEPROP 0 LASTPIN (-7225 4750) $PN 78
J 2
(-7235 4760);
DISPLAY 0.680851 (-7235 4760);
PAINT MONO (-7235 4760);
FORCEPROP 0 LASTPIN (-7225 5200) $PN 213
J 2
(-7235 5210);
DISPLAY 0.680851 (-7235 5210);
PAINT MONO (-7235 5210);
FORCEPROP 0 LASTPIN (-7225 4800) $PN 223
J 2
(-7235 4810);
DISPLAY 0.680851 (-7235 4810);
PAINT MONO (-7235 4810);
FORCEPROP 0 LASTPIN (-7225 5250) $PN 70
J 2
(-7235 5260);
DISPLAY 0.680851 (-7235 5260);
PAINT MONO (-7235 5260);
FORCEPROP 0 LASTPIN (-7225 4850) $PN 80
J 2
(-7235 4860);
DISPLAY 0.680851 (-7235 4860);
PAINT MONO (-7235 4860);
FORCEPROP 0 LASTPIN (-7225 5300) $PN 215
J 2
(-7235 5310);
DISPLAY 0.680851 (-7235 5310);
PAINT MONO (-7235 5310);
FORCEPROP 0 LASTPIN (-7225 4900) $PN 225
J 2
(-7235 4910);
DISPLAY 0.680851 (-7235 4910);
PAINT MONO (-7235 4910);
FORCEPROP 0 LASTPIN (-7225 5350) $PN 72
J 2
(-7235 5360);
DISPLAY 0.680851 (-7235 5360);
PAINT MONO (-7235 5360);
FORCEPROP 0 LASTPIN (-7225 4950) $PN 82
J 2
(-7235 4960);
DISPLAY 0.680851 (-7235 4960);
PAINT MONO (-7235 4960);
FORCEPROP 0 LASTPIN (-7225 3600) $PN 51
J 2
(-7235 3610);
DISPLAY 0.680851 (-7235 3610);
PAINT MONO (-7235 3610);
FORCEPROP 0 LASTPIN (-7225 3150) $PN 96
J 2
(-7235 3160);
DISPLAY 0.680851 (-7235 3160);
PAINT MONO (-7235 3160);
FORCEPROP 0 LASTPIN (-7225 3650) $PN 53
J 2
(-7235 3660);
DISPLAY 0.680851 (-7235 3660);
PAINT MONO (-7235 3660);
FORCEPROP 0 LASTPIN (-7225 3200) $PN 98
J 2
(-7235 3210);
DISPLAY 0.680851 (-7235 3210);
PAINT MONO (-7235 3210);
FORCEPROP 0 LASTPIN (-7225 3700) $PN 196
J 2
(-7235 3710);
DISPLAY 0.680851 (-7235 3710);
PAINT MONO (-7235 3710);
FORCEPROP 0 LASTPIN (-7225 3250) $PN 241
J 2
(-7235 3260);
DISPLAY 0.680851 (-7235 3260);
PAINT MONO (-7235 3260);
FORCEPROP 0 LASTPIN (-7225 3750) $PN 198
J 2
(-7235 3760);
DISPLAY 0.680851 (-7235 3760);
PAINT MONO (-7235 3760);
FORCEPROP 0 LASTPIN (-7225 3300) $PN 243
J 2
(-7235 3310);
DISPLAY 0.680851 (-7235 3310);
PAINT MONO (-7235 3310);
FORCEPROP 0 LASTPIN (-7225 3800) $PN 58
J 2
(-7235 3810);
DISPLAY 0.680851 (-7235 3810);
PAINT MONO (-7235 3810);
FORCEPROP 0 LASTPIN (-7225 3350) $PN 89
J 2
(-7235 3360);
DISPLAY 0.680851 (-7235 3360);
PAINT MONO (-7235 3360);
FORCEPROP 0 LASTPIN (-7225 3850) $PN 60
J 2
(-7235 3860);
DISPLAY 0.680851 (-7235 3860);
PAINT MONO (-7235 3860);
FORCEPROP 0 LASTPIN (-7225 3400) $PN 91
J 2
(-7235 3410);
DISPLAY 0.680851 (-7235 3410);
PAINT MONO (-7235 3410);
FORCEPROP 0 LASTPIN (-7225 3900) $PN 203
J 2
(-7235 3910);
DISPLAY 0.680851 (-7235 3910);
PAINT MONO (-7235 3910);
FORCEPROP 0 LASTPIN (-7225 3450) $PN 234
J 2
(-7235 3460);
DISPLAY 0.680851 (-7235 3460);
PAINT MONO (-7235 3460);
FORCEPROP 0 LASTPIN (-7225 3950) $PN 205
J 2
(-7235 3960);
DISPLAY 0.680851 (-7235 3960);
PAINT MONO (-7235 3960);
FORCEPROP 0 LASTPIN (-7225 3500) $PN 236
J 2
(-7235 3510);
DISPLAY 0.680851 (-7235 3510);
PAINT MONO (-7235 3510);
FORCEPROP 0 LASTPIN (-7225 4050) $PN 218
J 2
(-7235 4060);
DISPLAY 0.680851 (-7235 4060);
PAINT MONO (-7235 4060);
FORCEPROP 0 LASTPIN (-7225 4100) $PN 217
J 2
(-7235 4110);
DISPLAY 0.680851 (-7235 4110);
PAINT MONO (-7235 4110);
FORCEPROP 0 LASTPIN (-7225 4350) $PN 64
J 2
(-7235 4360);
DISPLAY 0.680851 (-7235 4360);
PAINT MONO (-7235 4360);
FORCEPROP 0 LASTPIN (-7225 4200) $PN 84
J 2
(-7235 4210);
DISPLAY 0.680851 (-7235 4210);
PAINT MONO (-7235 4210);
FORCEPROP 0 LASTPIN (-7225 4400) $PN 209
J 2
(-7235 4410);
DISPLAY 0.680851 (-7235 4410);
PAINT MONO (-7235 4410);
FORCEPROP 0 LASTPIN (-7225 4250) $PN 229
J 2
(-7235 4260);
DISPLAY 0.680851 (-7235 4260);
PAINT MONO (-7235 4260);
FORCEPROP 0 LASTPIN (-6025 3800) $PN 7
J 0
(-6015 3810);
DISPLAY 0.680851 (-6015 3810);
PAINT MONO (-6015 3810);
FORCEPROP 0 LASTPIN (-6025 2150) $PN 100
J 0
(-6015 2160);
DISPLAY 0.680851 (-6015 2160);
PAINT MONO (-6015 2160);
FORCEPROP 0 LASTPIN (-6025 3850) $PN 9
J 0
(-6015 3860);
DISPLAY 0.680851 (-6015 3860);
PAINT MONO (-6015 3860);
FORCEPROP 0 LASTPIN (-6025 2200) $PN 102
J 0
(-6015 2210);
DISPLAY 0.680851 (-6015 2210);
PAINT MONO (-6015 2210);
FORCEPROP 0 LASTPIN (-6025 3900) $PN 152
J 0
(-6015 3910);
DISPLAY 0.680851 (-6015 3910);
PAINT MONO (-6015 3910);
FORCEPROP 0 LASTPIN (-6025 2250) $PN 245
J 0
(-6015 2260);
DISPLAY 0.680851 (-6015 2260);
PAINT MONO (-6015 2260);
FORCEPROP 0 LASTPIN (-6025 3950) $PN 154
J 0
(-6015 3960);
DISPLAY 0.680851 (-6015 3960);
PAINT MONO (-6015 3960);
FORCEPROP 0 LASTPIN (-6025 2300) $PN 247
J 0
(-6015 2310);
DISPLAY 0.680851 (-6015 2310);
PAINT MONO (-6015 2310);
FORCEPROP 0 LASTPIN (-6025 4000) $PN 14
J 0
(-6015 4010);
DISPLAY 0.680851 (-6015 4010);
PAINT MONO (-6015 4010);
FORCEPROP 0 LASTPIN (-6025 2350) $PN 107
J 0
(-6015 2360);
DISPLAY 0.680851 (-6015 2360);
PAINT MONO (-6015 2360);
FORCEPROP 0 LASTPIN (-6025 4050) $PN 16
J 0
(-6015 4060);
DISPLAY 0.680851 (-6015 4060);
PAINT MONO (-6015 4060);
FORCEPROP 0 LASTPIN (-6025 2400) $PN 109
J 0
(-6015 2410);
DISPLAY 0.680851 (-6015 2410);
PAINT MONO (-6015 2410);
FORCEPROP 0 LASTPIN (-6025 4100) $PN 159
J 0
(-6015 4110);
DISPLAY 0.680851 (-6015 4110);
PAINT MONO (-6015 4110);
FORCEPROP 0 LASTPIN (-6025 2450) $PN 252
J 0
(-6015 2460);
DISPLAY 0.680851 (-6015 2460);
PAINT MONO (-6015 2460);
FORCEPROP 0 LASTPIN (-6025 4150) $PN 161
J 0
(-6015 4160);
DISPLAY 0.680851 (-6015 4160);
PAINT MONO (-6015 4160);
FORCEPROP 0 LASTPIN (-6025 2500) $PN 254
J 0
(-6015 2510);
DISPLAY 0.680851 (-6015 2510);
PAINT MONO (-6015 2510);
FORCEPROP 0 LASTPIN (-6025 4200) $PN 18
J 0
(-6015 4210);
DISPLAY 0.680851 (-6015 4210);
PAINT MONO (-6015 4210);
FORCEPROP 0 LASTPIN (-6025 2550) $PN 111
J 0
(-6015 2560);
DISPLAY 0.680851 (-6015 2560);
PAINT MONO (-6015 2560);
FORCEPROP 0 LASTPIN (-6025 4250) $PN 20
J 0
(-6015 4260);
DISPLAY 0.680851 (-6015 4260);
PAINT MONO (-6015 4260);
FORCEPROP 0 LASTPIN (-6025 2600) $PN 113
J 0
(-6015 2610);
DISPLAY 0.680851 (-6015 2610);
PAINT MONO (-6015 2610);
FORCEPROP 0 LASTPIN (-6025 4300) $PN 163
J 0
(-6015 4310);
DISPLAY 0.680851 (-6015 4310);
PAINT MONO (-6015 4310);
FORCEPROP 0 LASTPIN (-6025 2650) $PN 256
J 0
(-6015 2660);
DISPLAY 0.680851 (-6015 2660);
PAINT MONO (-6015 2660);
FORCEPROP 0 LASTPIN (-6025 4350) $PN 165
J 0
(-6015 4360);
DISPLAY 0.680851 (-6015 4360);
PAINT MONO (-6015 4360);
FORCEPROP 0 LASTPIN (-6025 2700) $PN 258
J 0
(-6015 2710);
DISPLAY 0.680851 (-6015 2710);
PAINT MONO (-6015 2710);
FORCEPROP 0 LASTPIN (-6025 4400) $PN 25
J 0
(-6015 4410);
DISPLAY 0.680851 (-6015 4410);
PAINT MONO (-6015 4410);
FORCEPROP 0 LASTPIN (-6025 2750) $PN 118
J 0
(-6015 2760);
DISPLAY 0.680851 (-6015 2760);
PAINT MONO (-6015 2760);
FORCEPROP 0 LASTPIN (-6025 4450) $PN 27
J 0
(-6015 4460);
DISPLAY 0.680851 (-6015 4460);
PAINT MONO (-6015 4460);
FORCEPROP 0 LASTPIN (-6025 2800) $PN 120
J 0
(-6015 2810);
DISPLAY 0.680851 (-6015 2810);
PAINT MONO (-6015 2810);
FORCEPROP 0 LASTPIN (-6025 4500) $PN 170
J 0
(-6015 4510);
DISPLAY 0.680851 (-6015 4510);
PAINT MONO (-6015 4510);
FORCEPROP 0 LASTPIN (-6025 2850) $PN 263
J 0
(-6015 2860);
DISPLAY 0.680851 (-6015 2860);
PAINT MONO (-6015 2860);
FORCEPROP 0 LASTPIN (-6025 4550) $PN 172
J 0
(-6015 4560);
DISPLAY 0.680851 (-6015 4560);
PAINT MONO (-6015 4560);
FORCEPROP 0 LASTPIN (-6025 2900) $PN 265
J 0
(-6015 2910);
DISPLAY 0.680851 (-6015 2910);
PAINT MONO (-6015 2910);
FORCEPROP 0 LASTPIN (-6025 4600) $PN 29
J 0
(-6015 4610);
DISPLAY 0.680851 (-6015 4610);
PAINT MONO (-6015 4610);
FORCEPROP 0 LASTPIN (-6025 2950) $PN 122
J 0
(-6015 2960);
DISPLAY 0.680851 (-6015 2960);
PAINT MONO (-6015 2960);
FORCEPROP 0 LASTPIN (-6025 4650) $PN 31
J 0
(-6015 4660);
DISPLAY 0.680851 (-6015 4660);
PAINT MONO (-6015 4660);
FORCEPROP 0 LASTPIN (-6025 3000) $PN 124
J 0
(-6015 3010);
DISPLAY 0.680851 (-6015 3010);
PAINT MONO (-6015 3010);
FORCEPROP 0 LASTPIN (-6025 4700) $PN 174
J 0
(-6015 4710);
DISPLAY 0.680851 (-6015 4710);
PAINT MONO (-6015 4710);
FORCEPROP 0 LASTPIN (-6025 3050) $PN 267
J 0
(-6015 3060);
DISPLAY 0.680851 (-6015 3060);
PAINT MONO (-6015 3060);
FORCEPROP 0 LASTPIN (-6025 4750) $PN 176
J 0
(-6015 4760);
DISPLAY 0.680851 (-6015 4760);
PAINT MONO (-6015 4760);
FORCEPROP 0 LASTPIN (-6025 3100) $PN 269
J 0
(-6015 3110);
DISPLAY 0.680851 (-6015 3110);
PAINT MONO (-6015 3110);
FORCEPROP 0 LASTPIN (-6025 4800) $PN 36
J 0
(-6015 4810);
DISPLAY 0.680851 (-6015 4810);
PAINT MONO (-6015 4810);
FORCEPROP 0 LASTPIN (-6025 3150) $PN 129
J 0
(-6015 3160);
DISPLAY 0.680851 (-6015 3160);
PAINT MONO (-6015 3160);
FORCEPROP 0 LASTPIN (-6025 4850) $PN 38
J 0
(-6015 4860);
DISPLAY 0.680851 (-6015 4860);
PAINT MONO (-6015 4860);
FORCEPROP 0 LASTPIN (-6025 3200) $PN 131
J 0
(-6015 3210);
DISPLAY 0.680851 (-6015 3210);
PAINT MONO (-6015 3210);
FORCEPROP 0 LASTPIN (-6025 4900) $PN 181
J 0
(-6015 4910);
DISPLAY 0.680851 (-6015 4910);
PAINT MONO (-6015 4910);
FORCEPROP 0 LASTPIN (-6025 3250) $PN 274
J 0
(-6015 3260);
DISPLAY 0.680851 (-6015 3260);
PAINT MONO (-6015 3260);
FORCEPROP 0 LASTPIN (-6025 4950) $PN 183
J 0
(-6015 4960);
DISPLAY 0.680851 (-6015 4960);
PAINT MONO (-6015 4960);
FORCEPROP 0 LASTPIN (-6025 3300) $PN 276
J 0
(-6015 3310);
DISPLAY 0.680851 (-6015 3310);
PAINT MONO (-6015 3310);
FORCEPROP 0 LASTPIN (-6025 5000) $PN 40
J 0
(-6015 5010);
DISPLAY 0.680851 (-6015 5010);
PAINT MONO (-6015 5010);
FORCEPROP 0 LASTPIN (-6025 3350) $PN 133
J 0
(-6015 3360);
DISPLAY 0.680851 (-6015 3360);
PAINT MONO (-6015 3360);
FORCEPROP 0 LASTPIN (-6025 5050) $PN 42
J 0
(-6015 5060);
DISPLAY 0.680851 (-6015 5060);
PAINT MONO (-6015 5060);
FORCEPROP 0 LASTPIN (-6025 3400) $PN 135
J 0
(-6015 3410);
DISPLAY 0.680851 (-6015 3410);
PAINT MONO (-6015 3410);
FORCEPROP 0 LASTPIN (-6025 5100) $PN 185
J 0
(-6015 5110);
DISPLAY 0.680851 (-6015 5110);
PAINT MONO (-6015 5110);
FORCEPROP 0 LASTPIN (-6025 3450) $PN 278
J 0
(-6015 3460);
DISPLAY 0.680851 (-6015 3460);
PAINT MONO (-6015 3460);
FORCEPROP 0 LASTPIN (-6025 5150) $PN 187
J 0
(-6015 5160);
DISPLAY 0.680851 (-6015 5160);
PAINT MONO (-6015 5160);
FORCEPROP 0 LASTPIN (-6025 3500) $PN 280
J 0
(-6015 3510);
DISPLAY 0.680851 (-6015 3510);
PAINT MONO (-6015 3510);
FORCEPROP 0 LASTPIN (-6025 5200) $PN 47
J 0
(-6015 5210);
DISPLAY 0.680851 (-6015 5210);
PAINT MONO (-6015 5210);
FORCEPROP 0 LASTPIN (-6025 3550) $PN 140
J 0
(-6015 3560);
DISPLAY 0.680851 (-6015 3560);
PAINT MONO (-6015 3560);
FORCEPROP 0 LASTPIN (-6025 5250) $PN 49
J 0
(-6015 5260);
DISPLAY 0.680851 (-6015 5260);
PAINT MONO (-6015 5260);
FORCEPROP 0 LASTPIN (-6025 3600) $PN 142
J 0
(-6015 3610);
DISPLAY 0.680851 (-6015 3610);
PAINT MONO (-6015 3610);
FORCEPROP 0 LASTPIN (-6025 5300) $PN 192
J 0
(-6015 5310);
DISPLAY 0.680851 (-6015 5310);
PAINT MONO (-6015 5310);
FORCEPROP 0 LASTPIN (-6025 3650) $PN 285
J 0
(-6015 3660);
DISPLAY 0.680851 (-6015 3660);
PAINT MONO (-6015 3660);
FORCEPROP 0 LASTPIN (-6025 5350) $PN 194
J 0
(-6015 5360);
DISPLAY 0.680851 (-6015 5360);
PAINT MONO (-6015 5360);
FORCEPROP 0 LASTPIN (-6025 3700) $PN 287
J 0
(-6015 3710);
DISPLAY 0.680851 (-6015 3710);
PAINT MONO (-6015 3710);
FORCEPROP 0 LASTPIN (-7225 2850) $PN 148
J 2
(-7235 2860);
DISPLAY 0.680851 (-7235 2860);
PAINT MONO (-7235 2860);
FORCEPROP 0 LASTPIN (-7225 2750) $PN 4
J 2
(-7235 2760);
DISPLAY 0.680851 (-7235 2760);
PAINT MONO (-7235 2760);
FORCEPROP 0 LASTPIN (-7225 2800) $PN 5
J 2
(-7235 2810);
DISPLAY 0.680851 (-7235 2810);
PAINT MONO (-7235 2810);
FORCEPROP 0 LASTPIN (-7225 1950) $PN 86
J 2
(-7235 1960);
DISPLAY 0.680851 (-7235 1960);
PAINT MONO (-7235 1960);
FORCEPROP 0 LASTPIN (-7225 1900) $PN 87
J 2
(-7235 1910);
DISPLAY 0.680851 (-7235 1910);
PAINT MONO (-7235 1910);
FORCEPROP 0 LASTPIN (-7225 4550) $PN 74
J 2
(-7235 4560);
DISPLAY 0.680851 (-7235 4560);
PAINT MONO (-7235 4560);
FORCEPROP 0 LASTPIN (-7225 4500) $PN 227
J 2
(-7235 4510);
DISPLAY 0.680851 (-7235 4510);
PAINT MONO (-7235 4510);
FORCEPROP 0 LASTPIN (-7225 2500) $PN 147
J 2
(-7235 2510);
DISPLAY 0.680851 (-7235 2510);
PAINT MONO (-7235 2510);
FORCEPROP 0 LASTPIN (-7225 3050) $PN 207
J 2
(-7235 3060);
DISPLAY 0.680851 (-7235 3060);
PAINT MONO (-7235 3060);
FORCEPROP 0 LASTPIN (-7225 2100) $PN 2
J 2
(-7235 2110);
DISPLAY 0.680851 (-7235 2110);
PAINT MONO (-7235 2110);
FORCEPROP 0 LASTPIN (-7225 2150) $PN 144
J 2
(-7235 2160);
DISPLAY 0.680851 (-7235 2160);
PAINT MONO (-7235 2160);
FORCEPROP 0 LASTPIN (-7225 2200) $PN 149
J 2
(-7235 2210);
DISPLAY 0.680851 (-7235 2210);
PAINT MONO (-7235 2210);
FORCEPROP 0 LASTPIN (-7225 2250) $PN 150
J 2
(-7235 2260);
DISPLAY 0.680851 (-7235 2260);
PAINT MONO (-7235 2260);
FORCEPROP 0 LASTPIN (-7225 2300) $PN 220
J 2
(-7235 2310);
DISPLAY 0.680851 (-7235 2310);
PAINT MONO (-7235 2310);
FORCEPROP 0 LASTPIN (-7225 2350) $PN 231
J 2
(-7235 2360);
DISPLAY 0.680851 (-7235 2360);
PAINT MONO (-7235 2360);
FORCEPROP 0 LASTPIN (-7225 2400) $PN 232
J 2
(-7235 2410);
DISPLAY 0.680851 (-7235 2410);
PAINT MONO (-7235 2410);
FORCEPROP 0 LASTPIN (-7225 2900) $PN 3
J 2
(-7235 2910);
DISPLAY 0.680851 (-7235 2910);
PAINT MONO (-7235 2910);
FORCEPROP 2 LAST VALUE SCONN288_DDR506112002KQ
J 0
(-7075 5725);
DISPLAY 0.489362 (-7075 5725);
PAINT SKYBLUE (-7075 5725);
FORCEPROP 2 LAST PART_TYPE SMLF
J 0
(-7075 5775);
DISPLAY 1.021277 (-7075 5775);
FORCEPROP 1 LAST MATERIAL IO
J 0
(-7075 5525);
DISPLAY 0.468085 (-7075 5525);
PAINT SKYBLUE (-7075 5525);
FORCEPROP 1 LAST PART_NUMBER DFHST8FS479
J 0
(-7075 5600);
DISPLAY 0.468085 (-7075 5600);
PAINT SKYBLUE (-7075 5600);
FORCEPROP 1 LAST CDS_LMAN_SYM_OUTLINE -450,1900,450,-1850
J 0
(-6625 3600);
DISPLAY 0.468085 (-6625 3600);
PAINT GREEN (-6625 3600);
DISPLAY INVISIBLE (-6625 3600);
FORCEPROP 1 LAST PATH I22
J 0
(-6625 3600);
DISPLAY 0.723404 (-6625 3600);
PAINT GREEN (-6625 3600);
DISPLAY INVISIBLE (-6625 3600);
FORCEPROP 1 LAST NEEDS_NO_SIZE TRUE
J 0
(-6625 3600);
DISPLAY 0.723404 (-6625 3600);
PAINT GREEN (-6625 3600);
DISPLAY INVISIBLE (-6625 3600);
FORCEPROP 2 LAST CDS_LIB pure_quanta
J 0
(-6625 3600);
DISPLAY INVISIBLE (-6625 3600);
FORCEADD TAP..1
(-3250 3375);
FORCEPROP 3 LASTPIN (-3300 3375) SIG_NAME M_G_CPU1_SB_DQS_DP<9>
J 0
(-3290 3385);
DISPLAY 0.659574 (-3290 3385);
PAINT MONO (-3290 3385);
DISPLAY INVISIBLE (-3290 3385);
FORCEPROP 1 LASTPIN (-3300 3375) BN 9
J 0
(-3312 3383);
DISPLAY 0.489362 (-3312 3383);
PAINT GREEN (-3312 3383);
FORCEPROP 2 LAST CDS_LIB mstr_standard
J 0
(-3250 3375);
DISPLAY 0.723404 (-3250 3375);
PAINT MONO (-3250 3375);
DISPLAY INVISIBLE (-3250 3375);
FORCEPROP 1 LAST BODY_TYPE PLUMBING
J 0
(-3250 3425);
DISPLAY 0.872340 (-3250 3425);
PAINT GREEN (-3250 3425);
DISPLAY INVISIBLE (-3250 3425);
FORCEPROP 1 LAST HDL_TAP TRUE
J 0
(-2925 3250);
DISPLAY 0.872340 (-2925 3250);
DISPLAY INVISIBLE (-2925 3250);
FORCEPROP 1 LAST PATH I220
J 0
(-3252 3375);
DISPLAY 0.872340 (-3252 3375);
PAINT GREEN (-3252 3375);
DISPLAY INVISIBLE (-3252 3375);
FORCEADD TAP..1
(-3250 3275);
FORCEPROP 3 LASTPIN (-3300 3275) SIG_NAME M_G_CPU1_SB_DQS_DP<8>
J 0
(-3290 3285);
DISPLAY 0.659574 (-3290 3285);
PAINT MONO (-3290 3285);
DISPLAY INVISIBLE (-3290 3285);
FORCEPROP 1 LASTPIN (-3300 3275) BN 8
J 0
(-3312 3283);
DISPLAY 0.489362 (-3312 3283);
PAINT GREEN (-3312 3283);
FORCEPROP 2 LAST CDS_LIB mstr_standard
J 0
(-3250 3275);
DISPLAY 0.723404 (-3250 3275);
PAINT MONO (-3250 3275);
DISPLAY INVISIBLE (-3250 3275);
FORCEPROP 1 LAST BODY_TYPE PLUMBING
J 0
(-3250 3325);
DISPLAY 0.872340 (-3250 3325);
PAINT GREEN (-3250 3325);
DISPLAY INVISIBLE (-3250 3325);
FORCEPROP 1 LAST HDL_TAP TRUE
J 0
(-2925 3150);
DISPLAY 0.872340 (-2925 3150);
DISPLAY INVISIBLE (-2925 3150);
FORCEPROP 1 LAST PATH I221
J 0
(-3252 3275);
DISPLAY 0.872340 (-3252 3275);
PAINT GREEN (-3252 3275);
DISPLAY INVISIBLE (-3252 3275);
FORCEADD TAP..1
(-3050 3125);
FORCEPROP 3 LASTPIN (-3100 3125) SIG_NAME M_G_CPU1_SB_DQS_DN<7>
J 0
(-3090 3135);
DISPLAY 0.659574 (-3090 3135);
PAINT MONO (-3090 3135);
DISPLAY INVISIBLE (-3090 3135);
FORCEPROP 1 LASTPIN (-3100 3125) BN 7
J 0
(-3112 3133);
DISPLAY 0.489362 (-3112 3133);
PAINT GREEN (-3112 3133);
FORCEPROP 2 LAST CDS_LIB mstr_standard
J 0
(-3050 3125);
DISPLAY 0.723404 (-3050 3125);
PAINT MONO (-3050 3125);
DISPLAY INVISIBLE (-3050 3125);
FORCEPROP 1 LAST BODY_TYPE PLUMBING
J 0
(-3050 3175);
DISPLAY 0.872340 (-3050 3175);
PAINT GREEN (-3050 3175);
DISPLAY INVISIBLE (-3050 3175);
FORCEPROP 1 LAST HDL_TAP TRUE
J 0
(-2725 3000);
DISPLAY 0.872340 (-2725 3000);
DISPLAY INVISIBLE (-2725 3000);
FORCEPROP 1 LAST PATH I222
J 0
(-3052 3125);
DISPLAY 0.872340 (-3052 3125);
PAINT GREEN (-3052 3125);
DISPLAY INVISIBLE (-3052 3125);
FORCEADD TAP..1
(-3050 3025);
FORCEPROP 3 LASTPIN (-3100 3025) SIG_NAME M_G_CPU1_SB_DQS_DN<6>
J 0
(-3090 3035);
DISPLAY 0.659574 (-3090 3035);
PAINT MONO (-3090 3035);
DISPLAY INVISIBLE (-3090 3035);
FORCEPROP 1 LASTPIN (-3100 3025) BN 6
J 0
(-3112 3033);
DISPLAY 0.489362 (-3112 3033);
PAINT GREEN (-3112 3033);
FORCEPROP 2 LAST CDS_LIB mstr_standard
J 0
(-3050 3025);
DISPLAY 0.723404 (-3050 3025);
PAINT MONO (-3050 3025);
DISPLAY INVISIBLE (-3050 3025);
FORCEPROP 1 LAST BODY_TYPE PLUMBING
J 0
(-3050 3075);
DISPLAY 0.872340 (-3050 3075);
PAINT GREEN (-3050 3075);
DISPLAY INVISIBLE (-3050 3075);
FORCEPROP 1 LAST HDL_TAP TRUE
J 0
(-2725 2900);
DISPLAY 0.872340 (-2725 2900);
DISPLAY INVISIBLE (-2725 2900);
FORCEPROP 1 LAST PATH I223
J 0
(-3052 3025);
DISPLAY 0.872340 (-3052 3025);
PAINT GREEN (-3052 3025);
DISPLAY INVISIBLE (-3052 3025);
FORCEADD TAP..1
(-3050 2925);
FORCEPROP 3 LASTPIN (-3100 2925) SIG_NAME M_G_CPU1_SB_DQS_DN<5>
J 0
(-3090 2935);
DISPLAY 0.659574 (-3090 2935);
PAINT MONO (-3090 2935);
DISPLAY INVISIBLE (-3090 2935);
FORCEPROP 1 LASTPIN (-3100 2925) BN 5
J 0
(-3112 2933);
DISPLAY 0.489362 (-3112 2933);
PAINT GREEN (-3112 2933);
FORCEPROP 2 LAST CDS_LIB mstr_standard
J 0
(-3050 2925);
DISPLAY 0.723404 (-3050 2925);
PAINT MONO (-3050 2925);
DISPLAY INVISIBLE (-3050 2925);
FORCEPROP 1 LAST BODY_TYPE PLUMBING
J 0
(-3050 2975);
DISPLAY 0.872340 (-3050 2975);
PAINT GREEN (-3050 2975);
DISPLAY INVISIBLE (-3050 2975);
FORCEPROP 1 LAST HDL_TAP TRUE
J 0
(-2725 2800);
DISPLAY 0.872340 (-2725 2800);
DISPLAY INVISIBLE (-2725 2800);
FORCEPROP 1 LAST PATH I224
J 0
(-3052 2925);
DISPLAY 0.872340 (-3052 2925);
PAINT GREEN (-3052 2925);
DISPLAY INVISIBLE (-3052 2925);
FORCEADD TAP..1
(-3050 2825);
FORCEPROP 3 LASTPIN (-3100 2825) SIG_NAME M_G_CPU1_SB_DQS_DN<4>
J 0
(-3090 2835);
DISPLAY 0.659574 (-3090 2835);
PAINT MONO (-3090 2835);
DISPLAY INVISIBLE (-3090 2835);
FORCEPROP 1 LASTPIN (-3100 2825) BN 4
J 0
(-3112 2833);
DISPLAY 0.489362 (-3112 2833);
PAINT GREEN (-3112 2833);
FORCEPROP 2 LAST CDS_LIB mstr_standard
J 0
(-3050 2825);
DISPLAY 0.723404 (-3050 2825);
PAINT MONO (-3050 2825);
DISPLAY INVISIBLE (-3050 2825);
FORCEPROP 1 LAST BODY_TYPE PLUMBING
J 0
(-3050 2875);
DISPLAY 0.872340 (-3050 2875);
PAINT GREEN (-3050 2875);
DISPLAY INVISIBLE (-3050 2875);
FORCEPROP 1 LAST HDL_TAP TRUE
J 0
(-2725 2700);
DISPLAY 0.872340 (-2725 2700);
DISPLAY INVISIBLE (-2725 2700);
FORCEPROP 1 LAST PATH I225
J 0
(-3052 2825);
DISPLAY 0.872340 (-3052 2825);
PAINT GREEN (-3052 2825);
DISPLAY INVISIBLE (-3052 2825);
FORCEADD TAP..1
(-3050 2725);
FORCEPROP 3 LASTPIN (-3100 2725) SIG_NAME M_G_CPU1_SB_DQS_DN<3>
J 0
(-3090 2735);
DISPLAY 0.659574 (-3090 2735);
PAINT MONO (-3090 2735);
DISPLAY INVISIBLE (-3090 2735);
FORCEPROP 1 LASTPIN (-3100 2725) BN 3
J 0
(-3112 2733);
DISPLAY 0.489362 (-3112 2733);
PAINT GREEN (-3112 2733);
FORCEPROP 2 LAST CDS_LIB mstr_standard
J 0
(-3050 2725);
DISPLAY 0.723404 (-3050 2725);
PAINT MONO (-3050 2725);
DISPLAY INVISIBLE (-3050 2725);
FORCEPROP 1 LAST BODY_TYPE PLUMBING
J 0
(-3050 2775);
DISPLAY 0.872340 (-3050 2775);
PAINT GREEN (-3050 2775);
DISPLAY INVISIBLE (-3050 2775);
FORCEPROP 1 LAST HDL_TAP TRUE
J 0
(-2725 2600);
DISPLAY 0.872340 (-2725 2600);
DISPLAY INVISIBLE (-2725 2600);
FORCEPROP 1 LAST PATH I226
J 0
(-3052 2725);
DISPLAY 0.872340 (-3052 2725);
PAINT GREEN (-3052 2725);
DISPLAY INVISIBLE (-3052 2725);
FORCEADD TAP..1
(-3250 3175);
FORCEPROP 3 LASTPIN (-3300 3175) SIG_NAME M_G_CPU1_SB_DQS_DP<7>
J 0
(-3290 3185);
DISPLAY 0.659574 (-3290 3185);
PAINT MONO (-3290 3185);
DISPLAY INVISIBLE (-3290 3185);
FORCEPROP 1 LASTPIN (-3300 3175) BN 7
J 0
(-3312 3183);
DISPLAY 0.489362 (-3312 3183);
PAINT GREEN (-3312 3183);
FORCEPROP 2 LAST CDS_LIB mstr_standard
J 0
(-3250 3175);
DISPLAY 0.723404 (-3250 3175);
PAINT MONO (-3250 3175);
DISPLAY INVISIBLE (-3250 3175);
FORCEPROP 1 LAST BODY_TYPE PLUMBING
J 0
(-3250 3225);
DISPLAY 0.872340 (-3250 3225);
PAINT GREEN (-3250 3225);
DISPLAY INVISIBLE (-3250 3225);
FORCEPROP 1 LAST HDL_TAP TRUE
J 0
(-2925 3050);
DISPLAY 0.872340 (-2925 3050);
DISPLAY INVISIBLE (-2925 3050);
FORCEPROP 1 LAST PATH I227
J 0
(-3252 3175);
DISPLAY 0.872340 (-3252 3175);
PAINT GREEN (-3252 3175);
DISPLAY INVISIBLE (-3252 3175);
FORCEADD TAP..1
(-3250 3075);
FORCEPROP 3 LASTPIN (-3300 3075) SIG_NAME M_G_CPU1_SB_DQS_DP<6>
J 0
(-3290 3085);
DISPLAY 0.659574 (-3290 3085);
PAINT MONO (-3290 3085);
DISPLAY INVISIBLE (-3290 3085);
FORCEPROP 1 LASTPIN (-3300 3075) BN 6
J 0
(-3312 3083);
DISPLAY 0.489362 (-3312 3083);
PAINT GREEN (-3312 3083);
FORCEPROP 2 LAST CDS_LIB mstr_standard
J 0
(-3250 3075);
DISPLAY 0.723404 (-3250 3075);
PAINT MONO (-3250 3075);
DISPLAY INVISIBLE (-3250 3075);
FORCEPROP 1 LAST BODY_TYPE PLUMBING
J 0
(-3250 3125);
DISPLAY 0.872340 (-3250 3125);
PAINT GREEN (-3250 3125);
DISPLAY INVISIBLE (-3250 3125);
FORCEPROP 1 LAST HDL_TAP TRUE
J 0
(-2925 2950);
DISPLAY 0.872340 (-2925 2950);
DISPLAY INVISIBLE (-2925 2950);
FORCEPROP 1 LAST PATH I228
J 0
(-3252 3075);
DISPLAY 0.872340 (-3252 3075);
PAINT GREEN (-3252 3075);
DISPLAY INVISIBLE (-3252 3075);
FORCEADD TAP..1
(-3250 2975);
FORCEPROP 3 LASTPIN (-3300 2975) SIG_NAME M_G_CPU1_SB_DQS_DP<5>
J 0
(-3290 2985);
DISPLAY 0.659574 (-3290 2985);
PAINT MONO (-3290 2985);
DISPLAY INVISIBLE (-3290 2985);
FORCEPROP 1 LASTPIN (-3300 2975) BN 5
J 0
(-3312 2983);
DISPLAY 0.489362 (-3312 2983);
PAINT GREEN (-3312 2983);
FORCEPROP 2 LAST CDS_LIB mstr_standard
J 0
(-3250 2975);
DISPLAY 0.723404 (-3250 2975);
PAINT MONO (-3250 2975);
DISPLAY INVISIBLE (-3250 2975);
FORCEPROP 1 LAST BODY_TYPE PLUMBING
J 0
(-3250 3025);
DISPLAY 0.872340 (-3250 3025);
PAINT GREEN (-3250 3025);
DISPLAY INVISIBLE (-3250 3025);
FORCEPROP 1 LAST HDL_TAP TRUE
J 0
(-2925 2850);
DISPLAY 0.872340 (-2925 2850);
DISPLAY INVISIBLE (-2925 2850);
FORCEPROP 1 LAST PATH I229
J 0
(-3252 2975);
DISPLAY 0.872340 (-3252 2975);
PAINT GREEN (-3252 2975);
DISPLAY INVISIBLE (-3252 2975);
FORCEADD TAP..1
R 2
(-7475 3200);
FORCEPROP 3 LASTPIN (-7425 3200) SIG_NAME M_G_CPU1_SB_CB<1>
J 0
(-7415 3210);
DISPLAY 0.659574 (-7415 3210);
PAINT MONO (-7415 3210);
DISPLAY INVISIBLE (-7415 3210);
FORCEPROP 1 LASTPIN (-7425 3200) BN 1
J 2
(-7413 3208);
DISPLAY 0.489362 (-7413 3208);
PAINT GREEN (-7413 3208);
FORCEPROP 2 LAST CDS_LIB mstr_standard
J 0
(-7475 3200);
DISPLAY 0.723404 (-7475 3200);
PAINT MONO (-7475 3200);
DISPLAY INVISIBLE (-7475 3200);
FORCEPROP 1 LAST BODY_TYPE PLUMBING
J 2
(-7475 3250);
DISPLAY 0.872340 (-7475 3250);
PAINT GREEN (-7475 3250);
DISPLAY INVISIBLE (-7475 3250);
FORCEPROP 1 LAST HDL_TAP TRUE
J 2
(-7800 3075);
DISPLAY 0.872340 (-7800 3075);
DISPLAY INVISIBLE (-7800 3075);
FORCEPROP 1 LAST PATH I23
J 2
(-7473 3200);
DISPLAY 0.872340 (-7473 3200);
PAINT GREEN (-7473 3200);
DISPLAY INVISIBLE (-7473 3200);
FORCEADD TAP..1
(-3250 2875);
FORCEPROP 3 LASTPIN (-3300 2875) SIG_NAME M_G_CPU1_SB_DQS_DP<4>
J 0
(-3290 2885);
DISPLAY 0.659574 (-3290 2885);
PAINT MONO (-3290 2885);
DISPLAY INVISIBLE (-3290 2885);
FORCEPROP 1 LASTPIN (-3300 2875) BN 4
J 0
(-3312 2883);
DISPLAY 0.489362 (-3312 2883);
PAINT GREEN (-3312 2883);
FORCEPROP 2 LAST CDS_LIB mstr_standard
J 0
(-3250 2875);
DISPLAY 0.723404 (-3250 2875);
PAINT MONO (-3250 2875);
DISPLAY INVISIBLE (-3250 2875);
FORCEPROP 1 LAST BODY_TYPE PLUMBING
J 0
(-3250 2925);
DISPLAY 0.872340 (-3250 2925);
PAINT GREEN (-3250 2925);
DISPLAY INVISIBLE (-3250 2925);
FORCEPROP 1 LAST HDL_TAP TRUE
J 0
(-2925 2750);
DISPLAY 0.872340 (-2925 2750);
DISPLAY INVISIBLE (-2925 2750);
FORCEPROP 1 LAST PATH I230
J 0
(-3252 2875);
DISPLAY 0.872340 (-3252 2875);
PAINT GREEN (-3252 2875);
DISPLAY INVISIBLE (-3252 2875);
FORCEADD TAP..1
(-3250 2775);
FORCEPROP 3 LASTPIN (-3300 2775) SIG_NAME M_G_CPU1_SB_DQS_DP<3>
J 0
(-3290 2785);
DISPLAY 0.659574 (-3290 2785);
PAINT MONO (-3290 2785);
DISPLAY INVISIBLE (-3290 2785);
FORCEPROP 1 LASTPIN (-3300 2775) BN 3
J 0
(-3312 2783);
DISPLAY 0.489362 (-3312 2783);
PAINT GREEN (-3312 2783);
FORCEPROP 2 LAST CDS_LIB mstr_standard
J 0
(-3250 2775);
DISPLAY 0.723404 (-3250 2775);
PAINT MONO (-3250 2775);
DISPLAY INVISIBLE (-3250 2775);
FORCEPROP 1 LAST BODY_TYPE PLUMBING
J 0
(-3250 2825);
DISPLAY 0.872340 (-3250 2825);
PAINT GREEN (-3250 2825);
DISPLAY INVISIBLE (-3250 2825);
FORCEPROP 1 LAST HDL_TAP TRUE
J 0
(-2925 2650);
DISPLAY 0.872340 (-2925 2650);
DISPLAY INVISIBLE (-2925 2650);
FORCEPROP 1 LAST PATH I231
J 0
(-3252 2775);
DISPLAY 0.872340 (-3252 2775);
PAINT GREEN (-3252 2775);
DISPLAY INVISIBLE (-3252 2775);
FORCEADD TAP..1
(-3050 2625);
FORCEPROP 3 LASTPIN (-3100 2625) SIG_NAME M_G_CPU1_SB_DQS_DN<2>
J 0
(-3090 2635);
DISPLAY 0.659574 (-3090 2635);
PAINT MONO (-3090 2635);
DISPLAY INVISIBLE (-3090 2635);
FORCEPROP 1 LASTPIN (-3100 2625) BN 2
J 0
(-3112 2633);
DISPLAY 0.489362 (-3112 2633);
PAINT GREEN (-3112 2633);
FORCEPROP 2 LAST CDS_LIB mstr_standard
J 0
(-3050 2625);
DISPLAY 0.723404 (-3050 2625);
PAINT MONO (-3050 2625);
DISPLAY INVISIBLE (-3050 2625);
FORCEPROP 1 LAST BODY_TYPE PLUMBING
J 0
(-3050 2675);
DISPLAY 0.872340 (-3050 2675);
PAINT GREEN (-3050 2675);
DISPLAY INVISIBLE (-3050 2675);
FORCEPROP 1 LAST HDL_TAP TRUE
J 0
(-2725 2500);
DISPLAY 0.872340 (-2725 2500);
DISPLAY INVISIBLE (-2725 2500);
FORCEPROP 1 LAST PATH I232
J 0
(-3052 2625);
DISPLAY 0.872340 (-3052 2625);
PAINT GREEN (-3052 2625);
DISPLAY INVISIBLE (-3052 2625);
FORCEADD TAP..1
(-3050 2525);
FORCEPROP 3 LASTPIN (-3100 2525) SIG_NAME M_G_CPU1_SB_DQS_DN<1>
J 0
(-3090 2535);
DISPLAY 0.659574 (-3090 2535);
PAINT MONO (-3090 2535);
DISPLAY INVISIBLE (-3090 2535);
FORCEPROP 1 LASTPIN (-3100 2525) BN 1
J 0
(-3112 2533);
DISPLAY 0.489362 (-3112 2533);
PAINT GREEN (-3112 2533);
FORCEPROP 2 LAST CDS_LIB mstr_standard
J 0
(-3050 2525);
DISPLAY 0.723404 (-3050 2525);
PAINT MONO (-3050 2525);
DISPLAY INVISIBLE (-3050 2525);
FORCEPROP 1 LAST BODY_TYPE PLUMBING
J 0
(-3050 2575);
DISPLAY 0.872340 (-3050 2575);
PAINT GREEN (-3050 2575);
DISPLAY INVISIBLE (-3050 2575);
FORCEPROP 1 LAST HDL_TAP TRUE
J 0
(-2725 2400);
DISPLAY 0.872340 (-2725 2400);
DISPLAY INVISIBLE (-2725 2400);
FORCEPROP 1 LAST PATH I233
J 0
(-3052 2525);
DISPLAY 0.872340 (-3052 2525);
PAINT GREEN (-3052 2525);
DISPLAY INVISIBLE (-3052 2525);
FORCEADD TAP..1
(-3050 2425);
FORCEPROP 3 LASTPIN (-3100 2425) SIG_NAME M_G_CPU1_SB_DQS_DN<0>
J 0
(-3090 2435);
DISPLAY 0.659574 (-3090 2435);
PAINT MONO (-3090 2435);
DISPLAY INVISIBLE (-3090 2435);
FORCEPROP 1 LASTPIN (-3100 2425) BN 0
J 0
(-3112 2433);
DISPLAY 0.489362 (-3112 2433);
PAINT GREEN (-3112 2433);
FORCEPROP 2 LAST CDS_LIB mstr_standard
J 0
(-3050 2425);
DISPLAY 0.723404 (-3050 2425);
PAINT MONO (-3050 2425);
DISPLAY INVISIBLE (-3050 2425);
FORCEPROP 1 LAST BODY_TYPE PLUMBING
J 0
(-3050 2475);
DISPLAY 0.872340 (-3050 2475);
PAINT GREEN (-3050 2475);
DISPLAY INVISIBLE (-3050 2475);
FORCEPROP 1 LAST HDL_TAP TRUE
J 0
(-2725 2300);
DISPLAY 0.872340 (-2725 2300);
DISPLAY INVISIBLE (-2725 2300);
FORCEPROP 1 LAST PATH I234
J 0
(-3052 2425);
DISPLAY 0.872340 (-3052 2425);
PAINT GREEN (-3052 2425);
DISPLAY INVISIBLE (-3052 2425);
FORCEADD TAP..1
(-3250 2675);
FORCEPROP 3 LASTPIN (-3300 2675) SIG_NAME M_G_CPU1_SB_DQS_DP<2>
J 0
(-3290 2685);
DISPLAY 0.659574 (-3290 2685);
PAINT MONO (-3290 2685);
DISPLAY INVISIBLE (-3290 2685);
FORCEPROP 1 LASTPIN (-3300 2675) BN 2
J 0
(-3312 2683);
DISPLAY 0.489362 (-3312 2683);
PAINT GREEN (-3312 2683);
FORCEPROP 2 LAST CDS_LIB mstr_standard
J 0
(-3250 2675);
DISPLAY 0.723404 (-3250 2675);
PAINT MONO (-3250 2675);
DISPLAY INVISIBLE (-3250 2675);
FORCEPROP 1 LAST BODY_TYPE PLUMBING
J 0
(-3250 2725);
DISPLAY 0.872340 (-3250 2725);
PAINT GREEN (-3250 2725);
DISPLAY INVISIBLE (-3250 2725);
FORCEPROP 1 LAST HDL_TAP TRUE
J 0
(-2925 2550);
DISPLAY 0.872340 (-2925 2550);
DISPLAY INVISIBLE (-2925 2550);
FORCEPROP 1 LAST PATH I235
J 0
(-3252 2675);
DISPLAY 0.872340 (-3252 2675);
PAINT GREEN (-3252 2675);
DISPLAY INVISIBLE (-3252 2675);
FORCEADD TAP..1
(-3250 2575);
FORCEPROP 3 LASTPIN (-3300 2575) SIG_NAME M_G_CPU1_SB_DQS_DP<1>
J 0
(-3290 2585);
DISPLAY 0.659574 (-3290 2585);
PAINT MONO (-3290 2585);
DISPLAY INVISIBLE (-3290 2585);
FORCEPROP 1 LASTPIN (-3300 2575) BN 1
J 0
(-3312 2583);
DISPLAY 0.489362 (-3312 2583);
PAINT GREEN (-3312 2583);
FORCEPROP 2 LAST CDS_LIB mstr_standard
J 0
(-3250 2575);
DISPLAY 0.723404 (-3250 2575);
PAINT MONO (-3250 2575);
DISPLAY INVISIBLE (-3250 2575);
FORCEPROP 1 LAST BODY_TYPE PLUMBING
J 0
(-3250 2625);
DISPLAY 0.872340 (-3250 2625);
PAINT GREEN (-3250 2625);
DISPLAY INVISIBLE (-3250 2625);
FORCEPROP 1 LAST HDL_TAP TRUE
J 0
(-2925 2450);
DISPLAY 0.872340 (-2925 2450);
DISPLAY INVISIBLE (-2925 2450);
FORCEPROP 1 LAST PATH I236
J 0
(-3252 2575);
DISPLAY 0.872340 (-3252 2575);
PAINT GREEN (-3252 2575);
DISPLAY INVISIBLE (-3252 2575);
FORCEADD TAP..1
(-3250 2475);
FORCEPROP 3 LASTPIN (-3300 2475) SIG_NAME M_G_CPU1_SB_DQS_DP<0>
J 0
(-3290 2485);
DISPLAY 0.659574 (-3290 2485);
PAINT MONO (-3290 2485);
DISPLAY INVISIBLE (-3290 2485);
FORCEPROP 1 LASTPIN (-3300 2475) BN 0
J 0
(-3312 2483);
DISPLAY 0.489362 (-3312 2483);
PAINT GREEN (-3312 2483);
FORCEPROP 2 LAST CDS_LIB mstr_standard
J 0
(-3250 2475);
DISPLAY 0.723404 (-3250 2475);
PAINT MONO (-3250 2475);
DISPLAY INVISIBLE (-3250 2475);
FORCEPROP 1 LAST BODY_TYPE PLUMBING
J 0
(-3250 2525);
DISPLAY 0.872340 (-3250 2525);
PAINT GREEN (-3250 2525);
DISPLAY INVISIBLE (-3250 2525);
FORCEPROP 1 LAST HDL_TAP TRUE
J 0
(-2925 2350);
DISPLAY 0.872340 (-2925 2350);
DISPLAY INVISIBLE (-2925 2350);
FORCEPROP 1 LAST PATH I237
J 0
(-3252 2475);
DISPLAY 0.872340 (-3252 2475);
PAINT GREEN (-3252 2475);
DISPLAY INVISIBLE (-3252 2475);
FORCEADD SCONN288_DDR506112002KQ..2
(-4250 3425);
FORCEPROP 1 LAST LOCATION J102
J 0
(-4850 4750);
DISPLAY 0.468085 (-4850 4750);
PAINT SKYBLUE (-4850 4750);
FORCEPROP 0 LAST $SEC 2
J 0
(-4700 4900);
DISPLAY 0.680851 (-4700 4900);
PAINT MONO (-4700 4900);
DISPLAY INVISIBLE (-4700 4900);
FORCEPROP 2 LAST CDS_SEC 2
J 0
(-4700 4900);
DISPLAY 0.680851 (-4700 4900);
DISPLAY INVISIBLE (-4700 4900);
FORCEPROP 0 LASTPIN (-3500 3475) $PN 12
J 0
(-3490 3485);
DISPLAY 0.680851 (-3490 3485);
PAINT MONO (-3490 3485);
FORCEPROP 0 LASTPIN (-3500 3525) $PN 11
J 0
(-3490 3535);
DISPLAY 0.680851 (-3490 3535);
PAINT MONO (-3490 3535);
FORCEPROP 0 LASTPIN (-3500 2425) $PN 105
J 0
(-3490 2435);
DISPLAY 0.680851 (-3490 2435);
PAINT MONO (-3490 2435);
FORCEPROP 0 LASTPIN (-3500 2475) $PN 104
J 0
(-3490 2485);
DISPLAY 0.680851 (-3490 2485);
PAINT MONO (-3490 2485);
FORCEPROP 0 LASTPIN (-3500 3575) $PN 23
J 0
(-3490 3585);
DISPLAY 0.680851 (-3490 3585);
PAINT MONO (-3490 3585);
FORCEPROP 0 LASTPIN (-3500 3625) $PN 22
J 0
(-3490 3635);
DISPLAY 0.680851 (-3490 3635);
PAINT MONO (-3490 3635);
FORCEPROP 0 LASTPIN (-3500 2525) $PN 116
J 0
(-3490 2535);
DISPLAY 0.680851 (-3490 2535);
PAINT MONO (-3490 2535);
FORCEPROP 0 LASTPIN (-3500 2575) $PN 115
J 0
(-3490 2585);
DISPLAY 0.680851 (-3490 2585);
PAINT MONO (-3490 2585);
FORCEPROP 0 LASTPIN (-3500 3675) $PN 34
J 0
(-3490 3685);
DISPLAY 0.680851 (-3490 3685);
PAINT MONO (-3490 3685);
FORCEPROP 0 LASTPIN (-3500 3725) $PN 33
J 0
(-3490 3735);
DISPLAY 0.680851 (-3490 3735);
PAINT MONO (-3490 3735);
FORCEPROP 0 LASTPIN (-3500 2625) $PN 127
J 0
(-3490 2635);
DISPLAY 0.680851 (-3490 2635);
PAINT MONO (-3490 2635);
FORCEPROP 0 LASTPIN (-3500 2675) $PN 126
J 0
(-3490 2685);
DISPLAY 0.680851 (-3490 2685);
PAINT MONO (-3490 2685);
FORCEPROP 0 LASTPIN (-3500 3775) $PN 45
J 0
(-3490 3785);
DISPLAY 0.680851 (-3490 3785);
PAINT MONO (-3490 3785);
FORCEPROP 0 LASTPIN (-3500 3825) $PN 44
J 0
(-3490 3835);
DISPLAY 0.680851 (-3490 3835);
PAINT MONO (-3490 3835);
FORCEPROP 0 LASTPIN (-3500 2725) $PN 138
J 0
(-3490 2735);
DISPLAY 0.680851 (-3490 2735);
PAINT MONO (-3490 2735);
FORCEPROP 0 LASTPIN (-3500 2775) $PN 137
J 0
(-3490 2785);
DISPLAY 0.680851 (-3490 2785);
PAINT MONO (-3490 2785);
FORCEPROP 0 LASTPIN (-3500 3875) $PN 56
J 0
(-3490 3885);
DISPLAY 0.680851 (-3490 3885);
PAINT MONO (-3490 3885);
FORCEPROP 0 LASTPIN (-3500 3925) $PN 55
J 0
(-3490 3935);
DISPLAY 0.680851 (-3490 3935);
PAINT MONO (-3490 3935);
FORCEPROP 0 LASTPIN (-3500 2825) $PN 238
J 0
(-3490 2835);
DISPLAY 0.680851 (-3490 2835);
PAINT MONO (-3490 2835);
FORCEPROP 0 LASTPIN (-3500 2875) $PN 239
J 0
(-3490 2885);
DISPLAY 0.680851 (-3490 2885);
PAINT MONO (-3490 2885);
FORCEPROP 0 LASTPIN (-3500 3975) $PN 156
J 0
(-3490 3985);
DISPLAY 0.680851 (-3490 3985);
PAINT MONO (-3490 3985);
FORCEPROP 0 LASTPIN (-3500 4025) $PN 157
J 0
(-3490 4035);
DISPLAY 0.680851 (-3490 4035);
PAINT MONO (-3490 4035);
FORCEPROP 0 LASTPIN (-3500 2925) $PN 249
J 0
(-3490 2935);
DISPLAY 0.680851 (-3490 2935);
PAINT MONO (-3490 2935);
FORCEPROP 0 LASTPIN (-3500 2975) $PN 250
J 0
(-3490 2985);
DISPLAY 0.680851 (-3490 2985);
PAINT MONO (-3490 2985);
FORCEPROP 0 LASTPIN (-3500 4075) $PN 167
J 0
(-3490 4085);
DISPLAY 0.680851 (-3490 4085);
PAINT MONO (-3490 4085);
FORCEPROP 0 LASTPIN (-3500 4125) $PN 168
J 0
(-3490 4135);
DISPLAY 0.680851 (-3490 4135);
PAINT MONO (-3490 4135);
FORCEPROP 0 LASTPIN (-3500 3025) $PN 260
J 0
(-3490 3035);
DISPLAY 0.680851 (-3490 3035);
PAINT MONO (-3490 3035);
FORCEPROP 0 LASTPIN (-3500 3075) $PN 261
J 0
(-3490 3085);
DISPLAY 0.680851 (-3490 3085);
PAINT MONO (-3490 3085);
FORCEPROP 0 LASTPIN (-3500 4175) $PN 178
J 0
(-3490 4185);
DISPLAY 0.680851 (-3490 4185);
PAINT MONO (-3490 4185);
FORCEPROP 0 LASTPIN (-3500 4225) $PN 179
J 0
(-3490 4235);
DISPLAY 0.680851 (-3490 4235);
PAINT MONO (-3490 4235);
FORCEPROP 0 LASTPIN (-3500 3125) $PN 271
J 0
(-3490 3135);
DISPLAY 0.680851 (-3490 3135);
PAINT MONO (-3490 3135);
FORCEPROP 0 LASTPIN (-3500 3175) $PN 272
J 0
(-3490 3185);
DISPLAY 0.680851 (-3490 3185);
PAINT MONO (-3490 3185);
FORCEPROP 0 LASTPIN (-3500 4275) $PN 189
J 0
(-3490 4285);
DISPLAY 0.680851 (-3490 4285);
PAINT MONO (-3490 4285);
FORCEPROP 0 LASTPIN (-3500 4325) $PN 190
J 0
(-3490 4335);
DISPLAY 0.680851 (-3490 4335);
PAINT MONO (-3490 4335);
FORCEPROP 0 LASTPIN (-3500 3225) $PN 282
J 0
(-3490 3235);
DISPLAY 0.680851 (-3490 3235);
PAINT MONO (-3490 3235);
FORCEPROP 0 LASTPIN (-3500 3275) $PN 283
J 0
(-3490 3285);
DISPLAY 0.680851 (-3490 3285);
PAINT MONO (-3490 3285);
FORCEPROP 0 LASTPIN (-3500 4375) $PN 200
J 0
(-3490 4385);
DISPLAY 0.680851 (-3490 4385);
PAINT MONO (-3490 4385);
FORCEPROP 0 LASTPIN (-3500 4425) $PN 201
J 0
(-3490 4435);
DISPLAY 0.680851 (-3490 4435);
PAINT MONO (-3490 4435);
FORCEPROP 0 LASTPIN (-3500 3325) $PN 94
J 0
(-3490 3335);
DISPLAY 0.680851 (-3490 3335);
PAINT MONO (-3490 3335);
FORCEPROP 0 LASTPIN (-3500 3375) $PN 93
J 0
(-3490 3385);
DISPLAY 0.680851 (-3490 3385);
PAINT MONO (-3490 3385);
FORCEPROP 2 LAST VALUE SCONN288_DDR506112002KQ
J 0
(-4700 4800);
DISPLAY 0.489362 (-4700 4800);
PAINT SKYBLUE (-4700 4800);
FORCEPROP 1 LAST MATERIAL IO
J 0
(-4850 4600);
DISPLAY 0.468085 (-4850 4600);
PAINT SKYBLUE (-4850 4600);
FORCEPROP 2 LAST PART_TYPE SMLF
J 0
(-4700 4850);
DISPLAY 1.021277 (-4700 4850);
FORCEPROP 1 LAST PART_NUMBER DFHST8FS479
J 0
(-4850 4675);
DISPLAY 0.468085 (-4850 4675);
PAINT SKYBLUE (-4850 4675);
FORCEPROP 1 LAST CDS_LMAN_SYM_OUTLINE -600,1150,600,-1150
J 0
(-4250 3425);
DISPLAY 0.468085 (-4250 3425);
PAINT GREEN (-4250 3425);
DISPLAY INVISIBLE (-4250 3425);
FORCEPROP 1 LAST PATH I238
J 0
(-4250 3425);
DISPLAY 0.723404 (-4250 3425);
PAINT GREEN (-4250 3425);
DISPLAY INVISIBLE (-4250 3425);
FORCEPROP 1 LAST NEEDS_NO_SIZE TRUE
J 0
(-4250 3425);
DISPLAY 0.723404 (-4250 3425);
PAINT GREEN (-4250 3425);
DISPLAY INVISIBLE (-4250 3425);
FORCEPROP 2 LAST CDS_LIB pure_quanta
J 0
(-4250 3425);
DISPLAY INVISIBLE (-4250 3425);
FORCEADD GND..1
(-2825 5525);
FORCEPROP 3 LASTPIN (-2825 5575) SIG_NAME GND\g
J 0
(-2815 5585);
DISPLAY 0.659574 (-2815 5585);
PAINT MONO (-2815 5585);
DISPLAY INVISIBLE (-2815 5585);
FORCEPROP 2 LAST CDS_LIB pure_quanta_power
J 0
(-2825 5525);
DISPLAY INVISIBLE (-2825 5525);
FORCEPROP 2 LAST BOM_COST MEM
J 0
(-2800 5650);
DISPLAY 0.659574 (-2800 5650);
DISPLAY INVISIBLE (-2800 5650);
FORCEPROP 1 LAST SIZE 1B
J 0
(-2750 5475);
DISPLAY 0.723404 (-2750 5475);
PAINT GREEN (-2750 5475);
DISPLAY INVISIBLE (-2750 5475);
FORCEPROP 1 LAST PATH I239
J 0
(-2750 5525);
DISPLAY 0.872340 (-2750 5525);
PAINT AQUA (-2750 5525);
DISPLAY INVISIBLE (-2750 5525);
FORCEPROP 2 LAST ROOM MEM_EFGH_DECOUPLING_CAPS
J 0
(-2800 5600);
DISPLAY 0.659574 (-2800 5600);
PAINT RED (-2800 5600);
DISPLAY INVISIBLE (-2800 5600);
FORCEPROP 1 LAST HDL_POWER GND
J 0
(-2825 5675);
DISPLAY 0.723404 (-2825 5675);
PAINT GREEN (-2825 5675);
DISPLAY INVISIBLE (-2825 5675);
FORCEADD TAP..1
R 2
(-7475 3150);
FORCEPROP 3 LASTPIN (-7425 3150) SIG_NAME M_G_CPU1_SB_CB<0>
J 0
(-7415 3160);
DISPLAY 0.659574 (-7415 3160);
PAINT MONO (-7415 3160);
DISPLAY INVISIBLE (-7415 3160);
FORCEPROP 1 LASTPIN (-7425 3150) BN 0
J 2
(-7413 3158);
DISPLAY 0.489362 (-7413 3158);
PAINT GREEN (-7413 3158);
FORCEPROP 2 LAST CDS_LIB mstr_standard
J 0
(-7475 3150);
DISPLAY 0.723404 (-7475 3150);
PAINT MONO (-7475 3150);
DISPLAY INVISIBLE (-7475 3150);
FORCEPROP 1 LAST BODY_TYPE PLUMBING
J 2
(-7475 3200);
DISPLAY 0.872340 (-7475 3200);
PAINT GREEN (-7475 3200);
DISPLAY INVISIBLE (-7475 3200);
FORCEPROP 1 LAST HDL_TAP TRUE
J 2
(-7800 3025);
DISPLAY 0.872340 (-7800 3025);
DISPLAY INVISIBLE (-7800 3025);
FORCEPROP 1 LAST PATH I24
J 2
(-7473 3150);
DISPLAY 0.872340 (-7473 3150);
PAINT GREEN (-7473 3150);
DISPLAY INVISIBLE (-7473 3150);
FORCEADD Q_CAP..1
R 2
(-2825 5875);
FORCEPROP 1 LAST LOCATION C530
J 2
(-2875 5975);
DISPLAY 0.489362 (-2875 5975);
PAINT SKYBLUE (-2875 5975);
FORCEPROP 0 LAST $SEC 1
J 0
(-2875 6025);
DISPLAY 0.680851 (-2875 6025);
PAINT MONO (-2875 6025);
DISPLAY INVISIBLE (-2875 6025);
FORCEPROP 0 LAST CDS_SEC 1
J 0
(-2875 6025);
DISPLAY 0.680851 (-2875 6025);
DISPLAY INVISIBLE (-2875 6025);
FORCEPROP 1 LASTPIN (-2825 5975) $PN 1
J 2
(-2835 5955);
DISPLAY 0.489362 (-2835 5955);
PAINT MONO (-2835 5955);
FORCEPROP 1 LASTPIN (-2825 5775) $PN 2
J 2
(-2835 5755);
DISPLAY 0.489362 (-2835 5755);
PAINT MONO (-2835 5755);
FORCEPROP 1 LAST MATERIAL X6S
J 2
(-2875 5775);
DISPLAY 0.489362 (-2875 5775);
PAINT SKYBLUE (-2875 5775);
FORCEPROP 1 LAST TOLERANCE 10%
J 2
(-2875 5825);
DISPLAY 0.489362 (-2875 5825);
PAINT SKYBLUE (-2875 5825);
FORCEPROP 1 LAST VOLTAGE 25V
J 2
(-2875 5875);
DISPLAY 0.489362 (-2875 5875);
PAINT SKYBLUE (-2875 5875);
FORCEPROP 1 LAST PACK_TYPE C0805
J 2
(-2875 5675);
DISPLAY 0.489362 (-2875 5675);
PAINT SKYBLUE (-2875 5675);
FORCEPROP 1 LAST PART_NUMBER CH6104KEA00
J 2
(-2875 5725);
DISPLAY 0.489362 (-2875 5725);
PAINT SKYBLUE (-2875 5725);
FORCEPROP 1 LAST VALUE 10UF
J 2
(-2875 5925);
DISPLAY 0.489362 (-2875 5925);
PAINT SKYBLUE (-2875 5925);
FORCEPROP 0 LAST BOM_COST MEM
J 2
(-2880 6020);
DISPLAY 0.595745 (-2880 6020);
PAINT MONO (-2880 6020);
DISPLAY INVISIBLE (-2880 6020);
FORCEPROP 2 LAST CDS_LIB pure_quanta
J 0
(-2825 5875);
DISPLAY INVISIBLE (-2825 5875);
FORCEPROP 1 LAST PATH I240
J 2
(-2875 6025);
DISPLAY 0.978723 (-2875 6025);
PAINT WHITE (-2875 6025);
DISPLAY INVISIBLE (-2875 6025);
FORCEPROP 0 LAST ROOM MEM_CH_A_CPU0_DIMM1
J 2
(-2880 6020);
DISPLAY 0.595745 (-2880 6020);
PAINT RED (-2880 6020);
DISPLAY INVISIBLE (-2880 6020);
FORCEADD Q_CAP..1
R 2
(-2250 5875);
FORCEPROP 1 LAST LOCATION C531
J 2
(-2300 5975);
DISPLAY 0.489362 (-2300 5975);
PAINT SKYBLUE (-2300 5975);
FORCEPROP 0 LAST $SEC 1
J 0
(-2300 6025);
DISPLAY 0.680851 (-2300 6025);
PAINT MONO (-2300 6025);
DISPLAY INVISIBLE (-2300 6025);
FORCEPROP 0 LAST CDS_SEC 1
J 0
(-2300 6025);
DISPLAY 0.680851 (-2300 6025);
DISPLAY INVISIBLE (-2300 6025);
FORCEPROP 1 LASTPIN (-2250 5975) $PN 1
J 2
(-2260 5955);
DISPLAY 0.489362 (-2260 5955);
PAINT MONO (-2260 5955);
FORCEPROP 1 LASTPIN (-2250 5775) $PN 2
J 2
(-2260 5755);
DISPLAY 0.489362 (-2260 5755);
PAINT MONO (-2260 5755);
FORCEPROP 1 LAST TOLERANCE 10%
J 2
(-2300 5825);
DISPLAY 0.489362 (-2300 5825);
PAINT SKYBLUE (-2300 5825);
FORCEPROP 1 LAST VALUE 10UF
J 2
(-2300 5925);
DISPLAY 0.489362 (-2300 5925);
PAINT SKYBLUE (-2300 5925);
FORCEPROP 1 LAST VOLTAGE 25V
J 2
(-2300 5875);
DISPLAY 0.489362 (-2300 5875);
PAINT SKYBLUE (-2300 5875);
FORCEPROP 1 LAST PACK_TYPE C0805
J 2
(-2300 5675);
DISPLAY 0.489362 (-2300 5675);
PAINT SKYBLUE (-2300 5675);
FORCEPROP 1 LAST PART_NUMBER CH6104KEA00
J 2
(-2300 5725);
DISPLAY 0.489362 (-2300 5725);
PAINT SKYBLUE (-2300 5725);
FORCEPROP 1 LAST MATERIAL X6S
J 2
(-2300 5775);
DISPLAY 0.489362 (-2300 5775);
PAINT SKYBLUE (-2300 5775);
FORCEPROP 0 LAST BOM_COST MEM
J 2
(-2305 6020);
DISPLAY 0.595745 (-2305 6020);
PAINT MONO (-2305 6020);
DISPLAY INVISIBLE (-2305 6020);
FORCEPROP 2 LAST CDS_LIB pure_quanta
J 0
(-2250 5875);
DISPLAY INVISIBLE (-2250 5875);
FORCEPROP 1 LAST PATH I241
J 2
(-2300 6025);
DISPLAY 0.978723 (-2300 6025);
PAINT WHITE (-2300 6025);
DISPLAY INVISIBLE (-2300 6025);
FORCEPROP 0 LAST ROOM MEM_CH_A_CPU0_DIMM1
J 2
(-2305 6020);
DISPLAY 0.595745 (-2305 6020);
PAINT RED (-2305 6020);
DISPLAY INVISIBLE (-2305 6020);
FORCEADD UNIVERSAL_POWER..1
(-2825 6200);
FORCEPROP 3 LASTPIN (-2825 6150) SIG_NAME P12V_MEM_1\g
J 0
(-2815 6160);
DISPLAY 0.659574 (-2815 6160);
PAINT MONO (-2815 6160);
DISPLAY INVISIBLE (-2815 6160);
FORCEPROP 1 LAST HDL_POWER P12V_MEM_1
J 1
(-2825 6250);
DISPLAY 0.489362 (-2825 6250);
PAINT GREEN (-2825 6250);
FORCEPROP 2 LAST CDS_LIB pure_quanta_power
J 0
(-2825 6200);
DISPLAY INVISIBLE (-2825 6200);
FORCEPROP 1 LAST PATH I242
J 0
(-2775 6225);
DISPLAY 0.872340 (-2775 6225);
PAINT AQUA (-2775 6225);
DISPLAY INVISIBLE (-2775 6225);
FORCEADD OFFPAGE..1
(-8100 2625);
FORCEPROP 2 LAST $XR5 108 
J 0
(-8952 2625);
DISPLAY 0.638298 (-8952 2625);
PAINT MONO (-8952 2625);
FORCEPROP 2 LAST $XR4 107 
J 0
(-8832 2625);
DISPLAY 0.638298 (-8832 2625);
PAINT MONO (-8832 2625);
FORCEPROP 2 LAST $XR3 106 
J 0
(-8712 2625);
DISPLAY 0.638298 (-8712 2625);
PAINT MONO (-8712 2625);
FORCEPROP 2 LAST $XR2 105 
J 0
(-8592 2625);
DISPLAY 0.638298 (-8592 2625);
PAINT MONO (-8592 2625);
FORCEPROP 2 LAST $XR1 104 
J 0
(-8472 2625);
DISPLAY 0.638298 (-8472 2625);
PAINT MONO (-8472 2625);
FORCEPROP 2 LAST $XR0 136 
J 0
(-8352 2625);
DISPLAY 0.638298 (-8352 2625);
PAINT MONO (-8352 2625);
FORCEPROP 2 LAST PATH I243
J 0
(-8375 2675);
DISPLAY 0.680851 (-8375 2675);
DISPLAY INVISIBLE (-8375 2675);
FORCEPROP 1 LAST COMMENT_BODY TRUE
J 0
(-7975 2525);
DISPLAY 0.872340 (-7975 2525);
PAINT GREEN (-7975 2525);
DISPLAY INVISIBLE (-7975 2525);
FORCEPROP 1 LAST OFFPAGE TRUE
J 0
(-7775 2500);
DISPLAY 0.872340 (-7775 2500);
PAINT GREEN (-7775 2500);
DISPLAY INVISIBLE (-7775 2500);
FORCEPROP 2 LAST CDS_LIB mstr_standard
J 0
(-8100 2625);
DISPLAY 0.808511 (-8100 2625);
DISPLAY INVISIBLE (-8100 2625);
FORCEADD Q_RES..1
(-7525 2625);
FORCEPROP 1 LAST $LOCATION R1586
J 0
(-7575 2650);
DISPLAY 0.510638 (-7575 2650);
PAINT SKYBLUE (-7575 2650);
FORCEPROP 0 LAST CDS_LOCATION R1586
J 0
(-7575 2725);
DISPLAY 0.680851 (-7575 2725);
DISPLAY INVISIBLE (-7575 2725);
FORCEPROP 0 LAST $SEC 1
J 0
(-7575 2725);
DISPLAY 0.680851 (-7575 2725);
PAINT MONO (-7575 2725);
DISPLAY INVISIBLE (-7575 2725);
FORCEPROP 0 LAST CDS_SEC 1
J 0
(-7575 2725);
DISPLAY 0.680851 (-7575 2725);
DISPLAY INVISIBLE (-7575 2725);
FORCEPROP 1 LASTPIN (-7625 2625) $PN 1
J 0
(-7613 2637);
DISPLAY 0.787234 (-7613 2637);
PAINT MONO (-7613 2637);
FORCEPROP 1 LASTPIN (-7425 2625) $PN 2
J 0
(-7463 2637);
DISPLAY 0.787234 (-7463 2637);
PAINT MONO (-7463 2637);
FORCEPROP 1 LAST VALUE 49.9
J 2
(-7375 2700);
DISPLAY 0.510638 (-7375 2700);
PAINT SKYBLUE (-7375 2700);
FORCEPROP 2 LAST CDS_LIB pure_quanta
J 0
(-7525 2625);
DISPLAY INVISIBLE (-7525 2625);
FORCEPROP 1 LAST PATH I244
J 0
(-7575 2775);
DISPLAY 0.978723 (-7575 2775);
PAINT WHITE (-7575 2775);
DISPLAY INVISIBLE (-7575 2775);
FORCEPROP 1 LAST PART_NUMBER CS04992FB07
J 0
(-7575 2725);
DISPLAY 0.978723 (-7575 2725);
DISPLAY INVISIBLE (-7575 2725);
FORCEPROP 1 LAST TOLERANCE 1%
J 0
(-7525 2525);
DISPLAY 0.978723 (-7525 2525);
DISPLAY INVISIBLE (-7525 2525);
FORCEPROP 1 LAST WATTAGE 1/16W
J 2
(-7550 2475);
DISPLAY 0.978723 (-7550 2475);
DISPLAY INVISIBLE (-7550 2475);
FORCEPROP 1 LAST PACK_TYPE 0402LF
J 0
(-7275 2475);
DISPLAY 0.978723 (-7275 2475);
DISPLAY INVISIBLE (-7275 2475);
FORCEPROP 1 LAST MATERIAL CHIP
J 0
(-7525 2475);
DISPLAY 0.978723 (-7525 2475);
DISPLAY INVISIBLE (-7525 2475);
FORCEADD TAP..1
R 2
(-7475 3350);
FORCEPROP 3 LASTPIN (-7425 3350) SIG_NAME M_G_CPU1_SB_CB<4>
J 0
(-7415 3360);
DISPLAY 0.659574 (-7415 3360);
PAINT MONO (-7415 3360);
DISPLAY INVISIBLE (-7415 3360);
FORCEPROP 1 LASTPIN (-7425 3350) BN 4
J 2
(-7413 3358);
DISPLAY 0.489362 (-7413 3358);
PAINT GREEN (-7413 3358);
FORCEPROP 2 LAST CDS_LIB mstr_standard
J 0
(-7475 3350);
DISPLAY 0.723404 (-7475 3350);
PAINT MONO (-7475 3350);
DISPLAY INVISIBLE (-7475 3350);
FORCEPROP 1 LAST BODY_TYPE PLUMBING
J 2
(-7475 3400);
DISPLAY 0.872340 (-7475 3400);
PAINT GREEN (-7475 3400);
DISPLAY INVISIBLE (-7475 3400);
FORCEPROP 1 LAST HDL_TAP TRUE
J 2
(-7800 3225);
DISPLAY 0.872340 (-7800 3225);
DISPLAY INVISIBLE (-7800 3225);
FORCEPROP 1 LAST PATH I25
J 2
(-7473 3350);
DISPLAY 0.872340 (-7473 3350);
PAINT GREEN (-7473 3350);
DISPLAY INVISIBLE (-7473 3350);
FORCEADD TAP..1
R 2
(-7475 3300);
FORCEPROP 3 LASTPIN (-7425 3300) SIG_NAME M_G_CPU1_SB_CB<3>
J 0
(-7415 3310);
DISPLAY 0.659574 (-7415 3310);
PAINT MONO (-7415 3310);
DISPLAY INVISIBLE (-7415 3310);
FORCEPROP 1 LASTPIN (-7425 3300) BN 3
J 2
(-7413 3308);
DISPLAY 0.489362 (-7413 3308);
PAINT GREEN (-7413 3308);
FORCEPROP 2 LAST CDS_LIB mstr_standard
J 0
(-7475 3300);
DISPLAY 0.723404 (-7475 3300);
PAINT MONO (-7475 3300);
DISPLAY INVISIBLE (-7475 3300);
FORCEPROP 1 LAST BODY_TYPE PLUMBING
J 2
(-7475 3350);
DISPLAY 0.872340 (-7475 3350);
PAINT GREEN (-7475 3350);
DISPLAY INVISIBLE (-7475 3350);
FORCEPROP 1 LAST HDL_TAP TRUE
J 2
(-7800 3175);
DISPLAY 0.872340 (-7800 3175);
DISPLAY INVISIBLE (-7800 3175);
FORCEPROP 1 LAST PATH I26
J 2
(-7473 3300);
DISPLAY 0.872340 (-7473 3300);
PAINT GREEN (-7473 3300);
DISPLAY INVISIBLE (-7473 3300);
FORCEADD TAP..1
R 2
(-7475 3250);
FORCEPROP 3 LASTPIN (-7425 3250) SIG_NAME M_G_CPU1_SB_CB<2>
J 0
(-7415 3260);
DISPLAY 0.659574 (-7415 3260);
PAINT MONO (-7415 3260);
DISPLAY INVISIBLE (-7415 3260);
FORCEPROP 1 LASTPIN (-7425 3250) BN 2
J 2
(-7413 3258);
DISPLAY 0.489362 (-7413 3258);
PAINT GREEN (-7413 3258);
FORCEPROP 2 LAST CDS_LIB mstr_standard
J 0
(-7475 3250);
DISPLAY 0.723404 (-7475 3250);
PAINT MONO (-7475 3250);
DISPLAY INVISIBLE (-7475 3250);
FORCEPROP 1 LAST BODY_TYPE PLUMBING
J 2
(-7475 3300);
DISPLAY 0.872340 (-7475 3300);
PAINT GREEN (-7475 3300);
DISPLAY INVISIBLE (-7475 3300);
FORCEPROP 1 LAST HDL_TAP TRUE
J 2
(-7800 3125);
DISPLAY 0.872340 (-7800 3125);
DISPLAY INVISIBLE (-7800 3125);
FORCEPROP 1 LAST PATH I27
J 2
(-7473 3250);
DISPLAY 0.872340 (-7473 3250);
PAINT GREEN (-7473 3250);
DISPLAY INVISIBLE (-7473 3250);
FORCEADD TAP..1
R 2
(-7475 3400);
FORCEPROP 3 LASTPIN (-7425 3400) SIG_NAME M_G_CPU1_SB_CB<5>
J 0
(-7415 3410);
DISPLAY 0.659574 (-7415 3410);
PAINT MONO (-7415 3410);
DISPLAY INVISIBLE (-7415 3410);
FORCEPROP 1 LASTPIN (-7425 3400) BN 5
J 2
(-7413 3408);
DISPLAY 0.489362 (-7413 3408);
PAINT GREEN (-7413 3408);
FORCEPROP 2 LAST CDS_LIB mstr_standard
J 0
(-7475 3400);
DISPLAY 0.723404 (-7475 3400);
PAINT MONO (-7475 3400);
DISPLAY INVISIBLE (-7475 3400);
FORCEPROP 1 LAST BODY_TYPE PLUMBING
J 2
(-7475 3450);
DISPLAY 0.872340 (-7475 3450);
PAINT GREEN (-7475 3450);
DISPLAY INVISIBLE (-7475 3450);
FORCEPROP 1 LAST HDL_TAP TRUE
J 2
(-7800 3275);
DISPLAY 0.872340 (-7800 3275);
DISPLAY INVISIBLE (-7800 3275);
FORCEPROP 1 LAST PATH I28
J 2
(-7473 3400);
DISPLAY 0.872340 (-7473 3400);
PAINT GREEN (-7473 3400);
DISPLAY INVISIBLE (-7473 3400);
FORCEADD TAP..1
R 2
(-7475 3450);
FORCEPROP 3 LASTPIN (-7425 3450) SIG_NAME M_G_CPU1_SB_CB<6>
J 0
(-7415 3460);
DISPLAY 0.659574 (-7415 3460);
PAINT MONO (-7415 3460);
DISPLAY INVISIBLE (-7415 3460);
FORCEPROP 1 LASTPIN (-7425 3450) BN 6
J 2
(-7413 3458);
DISPLAY 0.489362 (-7413 3458);
PAINT GREEN (-7413 3458);
FORCEPROP 2 LAST CDS_LIB mstr_standard
J 0
(-7475 3450);
DISPLAY 0.723404 (-7475 3450);
PAINT MONO (-7475 3450);
DISPLAY INVISIBLE (-7475 3450);
FORCEPROP 1 LAST BODY_TYPE PLUMBING
J 2
(-7475 3500);
DISPLAY 0.872340 (-7475 3500);
PAINT GREEN (-7475 3500);
DISPLAY INVISIBLE (-7475 3500);
FORCEPROP 1 LAST HDL_TAP TRUE
J 2
(-7800 3325);
DISPLAY 0.872340 (-7800 3325);
DISPLAY INVISIBLE (-7800 3325);
FORCEPROP 1 LAST PATH I29
J 2
(-7473 3450);
DISPLAY 0.872340 (-7473 3450);
PAINT GREEN (-7473 3450);
DISPLAY INVISIBLE (-7473 3450);
FORCEADD TAP..1
R 2
(-7475 3650);
FORCEPROP 3 LASTPIN (-7425 3650) SIG_NAME M_G_CPU1_SA_CB<1>
J 0
(-7415 3660);
DISPLAY 0.659574 (-7415 3660);
PAINT MONO (-7415 3660);
DISPLAY INVISIBLE (-7415 3660);
FORCEPROP 1 LASTPIN (-7425 3650) BN 1
J 2
(-7413 3658);
DISPLAY 0.489362 (-7413 3658);
PAINT GREEN (-7413 3658);
FORCEPROP 2 LAST CDS_LIB mstr_standard
J 0
(-7475 3650);
DISPLAY 0.723404 (-7475 3650);
PAINT MONO (-7475 3650);
DISPLAY INVISIBLE (-7475 3650);
FORCEPROP 1 LAST BODY_TYPE PLUMBING
J 2
(-7475 3700);
DISPLAY 0.872340 (-7475 3700);
PAINT GREEN (-7475 3700);
DISPLAY INVISIBLE (-7475 3700);
FORCEPROP 1 LAST HDL_TAP TRUE
J 2
(-7800 3525);
DISPLAY 0.872340 (-7800 3525);
DISPLAY INVISIBLE (-7800 3525);
FORCEPROP 1 LAST PATH I30
J 2
(-7473 3650);
DISPLAY 0.872340 (-7473 3650);
PAINT GREEN (-7473 3650);
DISPLAY INVISIBLE (-7473 3650);
FORCEADD TAP..1
R 2
(-7475 3700);
FORCEPROP 3 LASTPIN (-7425 3700) SIG_NAME M_G_CPU1_SA_CB<2>
J 0
(-7415 3710);
DISPLAY 0.659574 (-7415 3710);
PAINT MONO (-7415 3710);
DISPLAY INVISIBLE (-7415 3710);
FORCEPROP 1 LASTPIN (-7425 3700) BN 2
J 2
(-7413 3708);
DISPLAY 0.489362 (-7413 3708);
PAINT GREEN (-7413 3708);
FORCEPROP 2 LAST CDS_LIB mstr_standard
J 0
(-7475 3700);
DISPLAY 0.723404 (-7475 3700);
PAINT MONO (-7475 3700);
DISPLAY INVISIBLE (-7475 3700);
FORCEPROP 1 LAST BODY_TYPE PLUMBING
J 2
(-7475 3750);
DISPLAY 0.872340 (-7475 3750);
PAINT GREEN (-7475 3750);
DISPLAY INVISIBLE (-7475 3750);
FORCEPROP 1 LAST HDL_TAP TRUE
J 2
(-7800 3575);
DISPLAY 0.872340 (-7800 3575);
DISPLAY INVISIBLE (-7800 3575);
FORCEPROP 1 LAST PATH I31
J 2
(-7473 3700);
DISPLAY 0.872340 (-7473 3700);
PAINT GREEN (-7473 3700);
DISPLAY INVISIBLE (-7473 3700);
FORCEADD TAP..1
R 2
(-7475 3500);
FORCEPROP 3 LASTPIN (-7425 3500) SIG_NAME M_G_CPU1_SB_CB<7>
J 0
(-7415 3510);
DISPLAY 0.659574 (-7415 3510);
PAINT MONO (-7415 3510);
DISPLAY INVISIBLE (-7415 3510);
FORCEPROP 1 LASTPIN (-7425 3500) BN 7
J 2
(-7413 3508);
DISPLAY 0.489362 (-7413 3508);
PAINT GREEN (-7413 3508);
FORCEPROP 2 LAST CDS_LIB mstr_standard
J 0
(-7475 3500);
DISPLAY 0.723404 (-7475 3500);
PAINT MONO (-7475 3500);
DISPLAY INVISIBLE (-7475 3500);
FORCEPROP 1 LAST BODY_TYPE PLUMBING
J 2
(-7475 3550);
DISPLAY 0.872340 (-7475 3550);
PAINT GREEN (-7475 3550);
DISPLAY INVISIBLE (-7475 3550);
FORCEPROP 1 LAST HDL_TAP TRUE
J 2
(-7800 3375);
DISPLAY 0.872340 (-7800 3375);
DISPLAY INVISIBLE (-7800 3375);
FORCEPROP 1 LAST PATH I32
J 2
(-7473 3500);
DISPLAY 0.872340 (-7473 3500);
PAINT GREEN (-7473 3500);
DISPLAY INVISIBLE (-7473 3500);
FORCEADD TAP..1
R 2
(-7475 3600);
FORCEPROP 3 LASTPIN (-7425 3600) SIG_NAME M_G_CPU1_SA_CB<0>
J 0
(-7415 3610);
DISPLAY 0.659574 (-7415 3610);
PAINT MONO (-7415 3610);
DISPLAY INVISIBLE (-7415 3610);
FORCEPROP 1 LASTPIN (-7425 3600) BN 0
J 2
(-7413 3608);
DISPLAY 0.489362 (-7413 3608);
PAINT GREEN (-7413 3608);
FORCEPROP 2 LAST CDS_LIB mstr_standard
J 0
(-7475 3600);
DISPLAY 0.723404 (-7475 3600);
PAINT MONO (-7475 3600);
DISPLAY INVISIBLE (-7475 3600);
FORCEPROP 1 LAST BODY_TYPE PLUMBING
J 2
(-7475 3650);
DISPLAY 0.872340 (-7475 3650);
PAINT GREEN (-7475 3650);
DISPLAY INVISIBLE (-7475 3650);
FORCEPROP 1 LAST HDL_TAP TRUE
J 2
(-7800 3475);
DISPLAY 0.872340 (-7800 3475);
DISPLAY INVISIBLE (-7800 3475);
FORCEPROP 1 LAST PATH I33
J 2
(-7473 3600);
DISPLAY 0.872340 (-7473 3600);
PAINT GREEN (-7473 3600);
DISPLAY INVISIBLE (-7473 3600);
FORCEADD TAP..1
R 2
(-7475 3750);
FORCEPROP 3 LASTPIN (-7425 3750) SIG_NAME M_G_CPU1_SA_CB<3>
J 0
(-7415 3760);
DISPLAY 0.659574 (-7415 3760);
PAINT MONO (-7415 3760);
DISPLAY INVISIBLE (-7415 3760);
FORCEPROP 1 LASTPIN (-7425 3750) BN 3
J 2
(-7413 3758);
DISPLAY 0.489362 (-7413 3758);
PAINT GREEN (-7413 3758);
FORCEPROP 2 LAST CDS_LIB mstr_standard
J 0
(-7475 3750);
DISPLAY 0.723404 (-7475 3750);
PAINT MONO (-7475 3750);
DISPLAY INVISIBLE (-7475 3750);
FORCEPROP 1 LAST BODY_TYPE PLUMBING
J 2
(-7475 3800);
DISPLAY 0.872340 (-7475 3800);
PAINT GREEN (-7475 3800);
DISPLAY INVISIBLE (-7475 3800);
FORCEPROP 1 LAST HDL_TAP TRUE
J 2
(-7800 3625);
DISPLAY 0.872340 (-7800 3625);
DISPLAY INVISIBLE (-7800 3625);
FORCEPROP 1 LAST PATH I34
J 2
(-7473 3750);
DISPLAY 0.872340 (-7473 3750);
PAINT GREEN (-7473 3750);
DISPLAY INVISIBLE (-7473 3750);
FORCEADD TAP..1
(-5775 2200);
FORCEPROP 3 LASTPIN (-5825 2200) SIG_NAME M_G_CPU1_SB_DQ<1>
J 0
(-5815 2210);
DISPLAY 0.659574 (-5815 2210);
PAINT MONO (-5815 2210);
DISPLAY INVISIBLE (-5815 2210);
FORCEPROP 1 LASTPIN (-5825 2200) BN 1
J 0
(-5837 2208);
DISPLAY 0.489362 (-5837 2208);
PAINT GREEN (-5837 2208);
FORCEPROP 2 LAST CDS_LIB mstr_standard
J 0
(-5775 2200);
DISPLAY 0.723404 (-5775 2200);
PAINT MONO (-5775 2200);
DISPLAY INVISIBLE (-5775 2200);
FORCEPROP 1 LAST BODY_TYPE PLUMBING
J 0
(-5775 2250);
DISPLAY 0.872340 (-5775 2250);
PAINT GREEN (-5775 2250);
DISPLAY INVISIBLE (-5775 2250);
FORCEPROP 1 LAST HDL_TAP TRUE
J 0
(-5450 2075);
DISPLAY 0.872340 (-5450 2075);
DISPLAY INVISIBLE (-5450 2075);
FORCEPROP 1 LAST PATH I42
J 0
(-5777 2200);
DISPLAY 0.872340 (-5777 2200);
PAINT GREEN (-5777 2200);
DISPLAY INVISIBLE (-5777 2200);
FORCEADD TAP..1
(-5775 2150);
FORCEPROP 3 LASTPIN (-5825 2150) SIG_NAME M_G_CPU1_SB_DQ<0>
J 0
(-5815 2160);
DISPLAY 0.659574 (-5815 2160);
PAINT MONO (-5815 2160);
DISPLAY INVISIBLE (-5815 2160);
FORCEPROP 1 LASTPIN (-5825 2150) BN 0
J 0
(-5837 2158);
DISPLAY 0.489362 (-5837 2158);
PAINT GREEN (-5837 2158);
FORCEPROP 2 LAST CDS_LIB mstr_standard
J 0
(-5775 2150);
DISPLAY 0.723404 (-5775 2150);
PAINT MONO (-5775 2150);
DISPLAY INVISIBLE (-5775 2150);
FORCEPROP 1 LAST BODY_TYPE PLUMBING
J 0
(-5775 2200);
DISPLAY 0.872340 (-5775 2200);
PAINT GREEN (-5775 2200);
DISPLAY INVISIBLE (-5775 2200);
FORCEPROP 1 LAST HDL_TAP TRUE
J 0
(-5450 2025);
DISPLAY 0.872340 (-5450 2025);
DISPLAY INVISIBLE (-5450 2025);
FORCEPROP 1 LAST PATH I43
J 0
(-5777 2150);
DISPLAY 0.872340 (-5777 2150);
PAINT GREEN (-5777 2150);
DISPLAY INVISIBLE (-5777 2150);
FORCEADD TAP..1
(-5775 2400);
FORCEPROP 3 LASTPIN (-5825 2400) SIG_NAME M_G_CPU1_SB_DQ<5>
J 0
(-5815 2410);
DISPLAY 0.659574 (-5815 2410);
PAINT MONO (-5815 2410);
DISPLAY INVISIBLE (-5815 2410);
FORCEPROP 1 LASTPIN (-5825 2400) BN 5
J 0
(-5837 2408);
DISPLAY 0.489362 (-5837 2408);
PAINT GREEN (-5837 2408);
FORCEPROP 2 LAST CDS_LIB mstr_standard
J 0
(-5775 2400);
DISPLAY 0.723404 (-5775 2400);
PAINT MONO (-5775 2400);
DISPLAY INVISIBLE (-5775 2400);
FORCEPROP 1 LAST BODY_TYPE PLUMBING
J 0
(-5775 2450);
DISPLAY 0.872340 (-5775 2450);
PAINT GREEN (-5775 2450);
DISPLAY INVISIBLE (-5775 2450);
FORCEPROP 1 LAST HDL_TAP TRUE
J 0
(-5450 2275);
DISPLAY 0.872340 (-5450 2275);
DISPLAY INVISIBLE (-5450 2275);
FORCEPROP 1 LAST PATH I44
J 0
(-5777 2400);
DISPLAY 0.872340 (-5777 2400);
PAINT GREEN (-5777 2400);
DISPLAY INVISIBLE (-5777 2400);
FORCEADD TAP..1
(-5775 2450);
FORCEPROP 3 LASTPIN (-5825 2450) SIG_NAME M_G_CPU1_SB_DQ<6>
J 0
(-5815 2460);
DISPLAY 0.659574 (-5815 2460);
PAINT MONO (-5815 2460);
DISPLAY INVISIBLE (-5815 2460);
FORCEPROP 1 LASTPIN (-5825 2450) BN 6
J 0
(-5837 2458);
DISPLAY 0.489362 (-5837 2458);
PAINT GREEN (-5837 2458);
FORCEPROP 2 LAST CDS_LIB mstr_standard
J 0
(-5775 2450);
DISPLAY 0.723404 (-5775 2450);
PAINT MONO (-5775 2450);
DISPLAY INVISIBLE (-5775 2450);
FORCEPROP 1 LAST BODY_TYPE PLUMBING
J 0
(-5775 2500);
DISPLAY 0.872340 (-5775 2500);
PAINT GREEN (-5775 2500);
DISPLAY INVISIBLE (-5775 2500);
FORCEPROP 1 LAST HDL_TAP TRUE
J 0
(-5450 2325);
DISPLAY 0.872340 (-5450 2325);
DISPLAY INVISIBLE (-5450 2325);
FORCEPROP 1 LAST PATH I45
J 0
(-5777 2450);
DISPLAY 0.872340 (-5777 2450);
PAINT GREEN (-5777 2450);
DISPLAY INVISIBLE (-5777 2450);
FORCEADD TAP..1
(-5775 2250);
FORCEPROP 3 LASTPIN (-5825 2250) SIG_NAME M_G_CPU1_SB_DQ<2>
J 0
(-5815 2260);
DISPLAY 0.659574 (-5815 2260);
PAINT MONO (-5815 2260);
DISPLAY INVISIBLE (-5815 2260);
FORCEPROP 1 LASTPIN (-5825 2250) BN 2
J 0
(-5837 2258);
DISPLAY 0.489362 (-5837 2258);
PAINT GREEN (-5837 2258);
FORCEPROP 2 LAST CDS_LIB mstr_standard
J 0
(-5775 2250);
DISPLAY 0.723404 (-5775 2250);
PAINT MONO (-5775 2250);
DISPLAY INVISIBLE (-5775 2250);
FORCEPROP 1 LAST BODY_TYPE PLUMBING
J 0
(-5775 2300);
DISPLAY 0.872340 (-5775 2300);
PAINT GREEN (-5775 2300);
DISPLAY INVISIBLE (-5775 2300);
FORCEPROP 1 LAST HDL_TAP TRUE
J 0
(-5450 2125);
DISPLAY 0.872340 (-5450 2125);
DISPLAY INVISIBLE (-5450 2125);
FORCEPROP 1 LAST PATH I46
J 0
(-5777 2250);
DISPLAY 0.872340 (-5777 2250);
PAINT GREEN (-5777 2250);
DISPLAY INVISIBLE (-5777 2250);
FORCEADD TAP..1
(-5775 2300);
FORCEPROP 3 LASTPIN (-5825 2300) SIG_NAME M_G_CPU1_SB_DQ<3>
J 0
(-5815 2310);
DISPLAY 0.659574 (-5815 2310);
PAINT MONO (-5815 2310);
DISPLAY INVISIBLE (-5815 2310);
FORCEPROP 1 LASTPIN (-5825 2300) BN 3
J 0
(-5837 2308);
DISPLAY 0.489362 (-5837 2308);
PAINT GREEN (-5837 2308);
FORCEPROP 2 LAST CDS_LIB mstr_standard
J 0
(-5775 2300);
DISPLAY 0.723404 (-5775 2300);
PAINT MONO (-5775 2300);
DISPLAY INVISIBLE (-5775 2300);
FORCEPROP 1 LAST BODY_TYPE PLUMBING
J 0
(-5775 2350);
DISPLAY 0.872340 (-5775 2350);
PAINT GREEN (-5775 2350);
DISPLAY INVISIBLE (-5775 2350);
FORCEPROP 1 LAST HDL_TAP TRUE
J 0
(-5450 2175);
DISPLAY 0.872340 (-5450 2175);
DISPLAY INVISIBLE (-5450 2175);
FORCEPROP 1 LAST PATH I47
J 0
(-5777 2300);
DISPLAY 0.872340 (-5777 2300);
PAINT GREEN (-5777 2300);
DISPLAY INVISIBLE (-5777 2300);
FORCEADD TAP..1
(-5775 2350);
FORCEPROP 3 LASTPIN (-5825 2350) SIG_NAME M_G_CPU1_SB_DQ<4>
J 0
(-5815 2360);
DISPLAY 0.659574 (-5815 2360);
PAINT MONO (-5815 2360);
DISPLAY INVISIBLE (-5815 2360);
FORCEPROP 1 LASTPIN (-5825 2350) BN 4
J 0
(-5837 2358);
DISPLAY 0.489362 (-5837 2358);
PAINT GREEN (-5837 2358);
FORCEPROP 2 LAST CDS_LIB mstr_standard
J 0
(-5775 2350);
DISPLAY 0.723404 (-5775 2350);
PAINT MONO (-5775 2350);
DISPLAY INVISIBLE (-5775 2350);
FORCEPROP 1 LAST BODY_TYPE PLUMBING
J 0
(-5775 2400);
DISPLAY 0.872340 (-5775 2400);
PAINT GREEN (-5775 2400);
DISPLAY INVISIBLE (-5775 2400);
FORCEPROP 1 LAST HDL_TAP TRUE
J 0
(-5450 2225);
DISPLAY 0.872340 (-5450 2225);
DISPLAY INVISIBLE (-5450 2225);
FORCEPROP 1 LAST PATH I48
J 0
(-5777 2350);
DISPLAY 0.872340 (-5777 2350);
PAINT GREEN (-5777 2350);
DISPLAY INVISIBLE (-5777 2350);
FORCEADD TAP..1
(-5775 2650);
FORCEPROP 3 LASTPIN (-5825 2650) SIG_NAME M_G_CPU1_SB_DQ<10>
J 0
(-5815 2660);
DISPLAY 0.659574 (-5815 2660);
PAINT MONO (-5815 2660);
DISPLAY INVISIBLE (-5815 2660);
FORCEPROP 1 LASTPIN (-5825 2650) BN 10
J 0
(-5837 2658);
DISPLAY 0.489362 (-5837 2658);
PAINT GREEN (-5837 2658);
FORCEPROP 2 LAST CDS_LIB mstr_standard
J 0
(-5775 2650);
DISPLAY 0.723404 (-5775 2650);
PAINT MONO (-5775 2650);
DISPLAY INVISIBLE (-5775 2650);
FORCEPROP 1 LAST BODY_TYPE PLUMBING
J 0
(-5775 2700);
DISPLAY 0.872340 (-5775 2700);
PAINT GREEN (-5775 2700);
DISPLAY INVISIBLE (-5775 2700);
FORCEPROP 1 LAST HDL_TAP TRUE
J 0
(-5450 2525);
DISPLAY 0.872340 (-5450 2525);
DISPLAY INVISIBLE (-5450 2525);
FORCEPROP 1 LAST PATH I49
J 0
(-5777 2650);
DISPLAY 0.872340 (-5777 2650);
PAINT GREEN (-5777 2650);
DISPLAY INVISIBLE (-5777 2650);
FORCEADD VCC_CORE..1
(-8575 3425);
FORCEPROP 3 LASTPIN (-8575 3375) SIG_NAME P3V3_STBY\g
J 0
(-8565 3385);
DISPLAY 0.659574 (-8565 3385);
PAINT MONO (-8565 3385);
DISPLAY INVISIBLE (-8565 3385);
FORCEPROP 1 LAST HDL_POWER P3V3_STBY
J 1
(-8575 3475);
DISPLAY 0.489362 (-8575 3475);
PAINT GREEN (-8575 3475);
FORCEPROP 2 LAST CDS_LIB mstr_symbols
J 0
(-8575 3425);
PAINT MONO (-8575 3425);
DISPLAY INVISIBLE (-8575 3425);
FORCEPROP 1 LAST PATH I5
J 0
(-8525 3450);
DISPLAY 0.872340 (-8525 3450);
PAINT AQUA (-8525 3450);
DISPLAY INVISIBLE (-8525 3450);
FORCEPROP 0 LAST VOLTAGE 3.3
J 0
(-8850 3575);
DISPLAY 1.021277 (-8850 3575);
PAINT SKYBLUE (-8850 3575);
DISPLAY INVISIBLE (-8850 3575);
FORCEPROP 2 LAST ROOM PVCCINFAON_CPU1_CTRL
J 0
(-8575 3525);
DISPLAY 0.808511 (-8575 3525);
PAINT RED (-8575 3525);
DISPLAY INVISIBLE (-8575 3525);
FORCEADD TAP..1
(-5775 2700);
FORCEPROP 3 LASTPIN (-5825 2700) SIG_NAME M_G_CPU1_SB_DQ<11>
J 0
(-5815 2710);
DISPLAY 0.659574 (-5815 2710);
PAINT MONO (-5815 2710);
DISPLAY INVISIBLE (-5815 2710);
FORCEPROP 1 LASTPIN (-5825 2700) BN 11
J 0
(-5837 2708);
DISPLAY 0.489362 (-5837 2708);
PAINT GREEN (-5837 2708);
FORCEPROP 2 LAST CDS_LIB mstr_standard
J 0
(-5775 2700);
DISPLAY 0.723404 (-5775 2700);
PAINT MONO (-5775 2700);
DISPLAY INVISIBLE (-5775 2700);
FORCEPROP 1 LAST BODY_TYPE PLUMBING
J 0
(-5775 2750);
DISPLAY 0.872340 (-5775 2750);
PAINT GREEN (-5775 2750);
DISPLAY INVISIBLE (-5775 2750);
FORCEPROP 1 LAST HDL_TAP TRUE
J 0
(-5450 2575);
DISPLAY 0.872340 (-5450 2575);
DISPLAY INVISIBLE (-5450 2575);
FORCEPROP 1 LAST PATH I50
J 0
(-5777 2700);
DISPLAY 0.872340 (-5777 2700);
PAINT GREEN (-5777 2700);
DISPLAY INVISIBLE (-5777 2700);
FORCEADD TAP..1
(-5775 2500);
FORCEPROP 3 LASTPIN (-5825 2500) SIG_NAME M_G_CPU1_SB_DQ<7>
J 0
(-5815 2510);
DISPLAY 0.659574 (-5815 2510);
PAINT MONO (-5815 2510);
DISPLAY INVISIBLE (-5815 2510);
FORCEPROP 1 LASTPIN (-5825 2500) BN 7
J 0
(-5837 2508);
DISPLAY 0.489362 (-5837 2508);
PAINT GREEN (-5837 2508);
FORCEPROP 2 LAST CDS_LIB mstr_standard
J 0
(-5775 2500);
DISPLAY 0.723404 (-5775 2500);
PAINT MONO (-5775 2500);
DISPLAY INVISIBLE (-5775 2500);
FORCEPROP 1 LAST BODY_TYPE PLUMBING
J 0
(-5775 2550);
DISPLAY 0.872340 (-5775 2550);
PAINT GREEN (-5775 2550);
DISPLAY INVISIBLE (-5775 2550);
FORCEPROP 1 LAST HDL_TAP TRUE
J 0
(-5450 2375);
DISPLAY 0.872340 (-5450 2375);
DISPLAY INVISIBLE (-5450 2375);
FORCEPROP 1 LAST PATH I51
J 0
(-5777 2500);
DISPLAY 0.872340 (-5777 2500);
PAINT GREEN (-5777 2500);
DISPLAY INVISIBLE (-5777 2500);
FORCEADD TAP..1
(-5775 2550);
FORCEPROP 3 LASTPIN (-5825 2550) SIG_NAME M_G_CPU1_SB_DQ<8>
J 0
(-5815 2560);
DISPLAY 0.659574 (-5815 2560);
PAINT MONO (-5815 2560);
DISPLAY INVISIBLE (-5815 2560);
FORCEPROP 1 LASTPIN (-5825 2550) BN 8
J 0
(-5837 2558);
DISPLAY 0.489362 (-5837 2558);
PAINT GREEN (-5837 2558);
FORCEPROP 2 LAST CDS_LIB mstr_standard
J 0
(-5775 2550);
DISPLAY 0.723404 (-5775 2550);
PAINT MONO (-5775 2550);
DISPLAY INVISIBLE (-5775 2550);
FORCEPROP 1 LAST BODY_TYPE PLUMBING
J 0
(-5775 2600);
DISPLAY 0.872340 (-5775 2600);
PAINT GREEN (-5775 2600);
DISPLAY INVISIBLE (-5775 2600);
FORCEPROP 1 LAST HDL_TAP TRUE
J 0
(-5450 2425);
DISPLAY 0.872340 (-5450 2425);
DISPLAY INVISIBLE (-5450 2425);
FORCEPROP 1 LAST PATH I52
J 0
(-5777 2550);
DISPLAY 0.872340 (-5777 2550);
PAINT GREEN (-5777 2550);
DISPLAY INVISIBLE (-5777 2550);
FORCEADD TAP..1
(-5775 2600);
FORCEPROP 3 LASTPIN (-5825 2600) SIG_NAME M_G_CPU1_SB_DQ<9>
J 0
(-5815 2610);
DISPLAY 0.659574 (-5815 2610);
PAINT MONO (-5815 2610);
DISPLAY INVISIBLE (-5815 2610);
FORCEPROP 1 LASTPIN (-5825 2600) BN 9
J 0
(-5837 2608);
DISPLAY 0.489362 (-5837 2608);
PAINT GREEN (-5837 2608);
FORCEPROP 2 LAST CDS_LIB mstr_standard
J 0
(-5775 2600);
DISPLAY 0.723404 (-5775 2600);
PAINT MONO (-5775 2600);
DISPLAY INVISIBLE (-5775 2600);
FORCEPROP 1 LAST BODY_TYPE PLUMBING
J 0
(-5775 2650);
DISPLAY 0.872340 (-5775 2650);
PAINT GREEN (-5775 2650);
DISPLAY INVISIBLE (-5775 2650);
FORCEPROP 1 LAST HDL_TAP TRUE
J 0
(-5450 2475);
DISPLAY 0.872340 (-5450 2475);
DISPLAY INVISIBLE (-5450 2475);
FORCEPROP 1 LAST PATH I53
J 0
(-5777 2600);
DISPLAY 0.872340 (-5777 2600);
PAINT GREEN (-5777 2600);
DISPLAY INVISIBLE (-5777 2600);
FORCEADD TAP..1
(-5775 2950);
FORCEPROP 3 LASTPIN (-5825 2950) SIG_NAME M_G_CPU1_SB_DQ<16>
J 0
(-5815 2960);
DISPLAY 0.659574 (-5815 2960);
PAINT MONO (-5815 2960);
DISPLAY INVISIBLE (-5815 2960);
FORCEPROP 1 LASTPIN (-5825 2950) BN 16
J 0
(-5837 2958);
DISPLAY 0.489362 (-5837 2958);
PAINT GREEN (-5837 2958);
FORCEPROP 2 LAST CDS_LIB mstr_standard
J 0
(-5775 2950);
DISPLAY 0.723404 (-5775 2950);
PAINT MONO (-5775 2950);
DISPLAY INVISIBLE (-5775 2950);
FORCEPROP 1 LAST BODY_TYPE PLUMBING
J 0
(-5775 3000);
DISPLAY 0.872340 (-5775 3000);
PAINT GREEN (-5775 3000);
DISPLAY INVISIBLE (-5775 3000);
FORCEPROP 1 LAST HDL_TAP TRUE
J 0
(-5450 2825);
DISPLAY 0.872340 (-5450 2825);
DISPLAY INVISIBLE (-5450 2825);
FORCEPROP 1 LAST PATH I54
J 0
(-5777 2950);
DISPLAY 0.872340 (-5777 2950);
PAINT GREEN (-5777 2950);
DISPLAY INVISIBLE (-5777 2950);
FORCEADD TAP..1
(-5775 2900);
FORCEPROP 3 LASTPIN (-5825 2900) SIG_NAME M_G_CPU1_SB_DQ<15>
J 0
(-5815 2910);
DISPLAY 0.659574 (-5815 2910);
PAINT MONO (-5815 2910);
DISPLAY INVISIBLE (-5815 2910);
FORCEPROP 1 LASTPIN (-5825 2900) BN 15
J 0
(-5837 2908);
DISPLAY 0.489362 (-5837 2908);
PAINT GREEN (-5837 2908);
FORCEPROP 2 LAST CDS_LIB mstr_standard
J 0
(-5775 2900);
DISPLAY 0.723404 (-5775 2900);
PAINT MONO (-5775 2900);
DISPLAY INVISIBLE (-5775 2900);
FORCEPROP 1 LAST BODY_TYPE PLUMBING
J 0
(-5775 2950);
DISPLAY 0.872340 (-5775 2950);
PAINT GREEN (-5775 2950);
DISPLAY INVISIBLE (-5775 2950);
FORCEPROP 1 LAST HDL_TAP TRUE
J 0
(-5450 2775);
DISPLAY 0.872340 (-5450 2775);
DISPLAY INVISIBLE (-5450 2775);
FORCEPROP 1 LAST PATH I55
J 0
(-5777 2900);
DISPLAY 0.872340 (-5777 2900);
PAINT GREEN (-5777 2900);
DISPLAY INVISIBLE (-5777 2900);
FORCEADD TAP..1
(-5775 3000);
FORCEPROP 3 LASTPIN (-5825 3000) SIG_NAME M_G_CPU1_SB_DQ<17>
J 0
(-5815 3010);
DISPLAY 0.659574 (-5815 3010);
PAINT MONO (-5815 3010);
DISPLAY INVISIBLE (-5815 3010);
FORCEPROP 1 LASTPIN (-5825 3000) BN 17
J 0
(-5837 3008);
DISPLAY 0.489362 (-5837 3008);
PAINT GREEN (-5837 3008);
FORCEPROP 2 LAST CDS_LIB mstr_standard
J 0
(-5775 3000);
DISPLAY 0.723404 (-5775 3000);
PAINT MONO (-5775 3000);
DISPLAY INVISIBLE (-5775 3000);
FORCEPROP 1 LAST BODY_TYPE PLUMBING
J 0
(-5775 3050);
DISPLAY 0.872340 (-5775 3050);
PAINT GREEN (-5775 3050);
DISPLAY INVISIBLE (-5775 3050);
FORCEPROP 1 LAST HDL_TAP TRUE
J 0
(-5450 2875);
DISPLAY 0.872340 (-5450 2875);
DISPLAY INVISIBLE (-5450 2875);
FORCEPROP 1 LAST PATH I56
J 0
(-5777 3000);
DISPLAY 0.872340 (-5777 3000);
PAINT GREEN (-5777 3000);
DISPLAY INVISIBLE (-5777 3000);
FORCEADD TAP..1
(-5775 2750);
FORCEPROP 3 LASTPIN (-5825 2750) SIG_NAME M_G_CPU1_SB_DQ<12>
J 0
(-5815 2760);
DISPLAY 0.659574 (-5815 2760);
PAINT MONO (-5815 2760);
DISPLAY INVISIBLE (-5815 2760);
FORCEPROP 1 LASTPIN (-5825 2750) BN 12
J 0
(-5837 2758);
DISPLAY 0.489362 (-5837 2758);
PAINT GREEN (-5837 2758);
FORCEPROP 2 LAST CDS_LIB mstr_standard
J 0
(-5775 2750);
DISPLAY 0.723404 (-5775 2750);
PAINT MONO (-5775 2750);
DISPLAY INVISIBLE (-5775 2750);
FORCEPROP 1 LAST BODY_TYPE PLUMBING
J 0
(-5775 2800);
DISPLAY 0.872340 (-5775 2800);
PAINT GREEN (-5775 2800);
DISPLAY INVISIBLE (-5775 2800);
FORCEPROP 1 LAST HDL_TAP TRUE
J 0
(-5450 2625);
DISPLAY 0.872340 (-5450 2625);
DISPLAY INVISIBLE (-5450 2625);
FORCEPROP 1 LAST PATH I57
J 0
(-5777 2750);
DISPLAY 0.872340 (-5777 2750);
PAINT GREEN (-5777 2750);
DISPLAY INVISIBLE (-5777 2750);
FORCEADD TAP..1
(-5775 2800);
FORCEPROP 3 LASTPIN (-5825 2800) SIG_NAME M_G_CPU1_SB_DQ<13>
J 0
(-5815 2810);
DISPLAY 0.659574 (-5815 2810);
PAINT MONO (-5815 2810);
DISPLAY INVISIBLE (-5815 2810);
FORCEPROP 1 LASTPIN (-5825 2800) BN 13
J 0
(-5837 2808);
DISPLAY 0.489362 (-5837 2808);
PAINT GREEN (-5837 2808);
FORCEPROP 2 LAST CDS_LIB mstr_standard
J 0
(-5775 2800);
DISPLAY 0.723404 (-5775 2800);
PAINT MONO (-5775 2800);
DISPLAY INVISIBLE (-5775 2800);
FORCEPROP 1 LAST BODY_TYPE PLUMBING
J 0
(-5775 2850);
DISPLAY 0.872340 (-5775 2850);
PAINT GREEN (-5775 2850);
DISPLAY INVISIBLE (-5775 2850);
FORCEPROP 1 LAST HDL_TAP TRUE
J 0
(-5450 2675);
DISPLAY 0.872340 (-5450 2675);
DISPLAY INVISIBLE (-5450 2675);
FORCEPROP 1 LAST PATH I58
J 0
(-5777 2800);
DISPLAY 0.872340 (-5777 2800);
PAINT GREEN (-5777 2800);
DISPLAY INVISIBLE (-5777 2800);
FORCEADD TAP..1
(-5775 2850);
FORCEPROP 3 LASTPIN (-5825 2850) SIG_NAME M_G_CPU1_SB_DQ<14>
J 0
(-5815 2860);
DISPLAY 0.659574 (-5815 2860);
PAINT MONO (-5815 2860);
DISPLAY INVISIBLE (-5815 2860);
FORCEPROP 1 LASTPIN (-5825 2850) BN 14
J 0
(-5837 2858);
DISPLAY 0.489362 (-5837 2858);
PAINT GREEN (-5837 2858);
FORCEPROP 2 LAST CDS_LIB mstr_standard
J 0
(-5775 2850);
DISPLAY 0.723404 (-5775 2850);
PAINT MONO (-5775 2850);
DISPLAY INVISIBLE (-5775 2850);
FORCEPROP 1 LAST BODY_TYPE PLUMBING
J 0
(-5775 2900);
DISPLAY 0.872340 (-5775 2900);
PAINT GREEN (-5775 2900);
DISPLAY INVISIBLE (-5775 2900);
FORCEPROP 1 LAST HDL_TAP TRUE
J 0
(-5450 2725);
DISPLAY 0.872340 (-5450 2725);
DISPLAY INVISIBLE (-5450 2725);
FORCEPROP 1 LAST PATH I59
J 0
(-5777 2850);
DISPLAY 0.872340 (-5777 2850);
PAINT GREEN (-5777 2850);
DISPLAY INVISIBLE (-5777 2850);
FORCEADD TAP..1
(-5775 3150);
FORCEPROP 3 LASTPIN (-5825 3150) SIG_NAME M_G_CPU1_SB_DQ<20>
J 0
(-5815 3160);
DISPLAY 0.659574 (-5815 3160);
PAINT MONO (-5815 3160);
DISPLAY INVISIBLE (-5815 3160);
FORCEPROP 1 LASTPIN (-5825 3150) BN 20
J 0
(-5837 3158);
DISPLAY 0.489362 (-5837 3158);
PAINT GREEN (-5837 3158);
FORCEPROP 2 LAST CDS_LIB mstr_standard
J 0
(-5775 3150);
DISPLAY 0.723404 (-5775 3150);
PAINT MONO (-5775 3150);
DISPLAY INVISIBLE (-5775 3150);
FORCEPROP 1 LAST BODY_TYPE PLUMBING
J 0
(-5775 3200);
DISPLAY 0.872340 (-5775 3200);
PAINT GREEN (-5775 3200);
DISPLAY INVISIBLE (-5775 3200);
FORCEPROP 1 LAST HDL_TAP TRUE
J 0
(-5450 3025);
DISPLAY 0.872340 (-5450 3025);
DISPLAY INVISIBLE (-5450 3025);
FORCEPROP 1 LAST PATH I60
J 0
(-5777 3150);
DISPLAY 0.872340 (-5777 3150);
PAINT GREEN (-5777 3150);
DISPLAY INVISIBLE (-5777 3150);
FORCEADD TAP..1
(-5775 3200);
FORCEPROP 3 LASTPIN (-5825 3200) SIG_NAME M_G_CPU1_SB_DQ<21>
J 0
(-5815 3210);
DISPLAY 0.659574 (-5815 3210);
PAINT MONO (-5815 3210);
DISPLAY INVISIBLE (-5815 3210);
FORCEPROP 1 LASTPIN (-5825 3200) BN 21
J 0
(-5837 3208);
DISPLAY 0.489362 (-5837 3208);
PAINT GREEN (-5837 3208);
FORCEPROP 2 LAST CDS_LIB mstr_standard
J 0
(-5775 3200);
DISPLAY 0.723404 (-5775 3200);
PAINT MONO (-5775 3200);
DISPLAY INVISIBLE (-5775 3200);
FORCEPROP 1 LAST BODY_TYPE PLUMBING
J 0
(-5775 3250);
DISPLAY 0.872340 (-5775 3250);
PAINT GREEN (-5775 3250);
DISPLAY INVISIBLE (-5775 3250);
FORCEPROP 1 LAST HDL_TAP TRUE
J 0
(-5450 3075);
DISPLAY 0.872340 (-5450 3075);
DISPLAY INVISIBLE (-5450 3075);
FORCEPROP 1 LAST PATH I61
J 0
(-5777 3200);
DISPLAY 0.872340 (-5777 3200);
PAINT GREEN (-5777 3200);
DISPLAY INVISIBLE (-5777 3200);
FORCEADD TAP..1
(-5775 3250);
FORCEPROP 3 LASTPIN (-5825 3250) SIG_NAME M_G_CPU1_SB_DQ<22>
J 0
(-5815 3260);
DISPLAY 0.659574 (-5815 3260);
PAINT MONO (-5815 3260);
DISPLAY INVISIBLE (-5815 3260);
FORCEPROP 1 LASTPIN (-5825 3250) BN 22
J 0
(-5837 3258);
DISPLAY 0.489362 (-5837 3258);
PAINT GREEN (-5837 3258);
FORCEPROP 2 LAST CDS_LIB mstr_standard
J 0
(-5775 3250);
DISPLAY 0.723404 (-5775 3250);
PAINT MONO (-5775 3250);
DISPLAY INVISIBLE (-5775 3250);
FORCEPROP 1 LAST BODY_TYPE PLUMBING
J 0
(-5775 3300);
DISPLAY 0.872340 (-5775 3300);
PAINT GREEN (-5775 3300);
DISPLAY INVISIBLE (-5775 3300);
FORCEPROP 1 LAST HDL_TAP TRUE
J 0
(-5450 3125);
DISPLAY 0.872340 (-5450 3125);
DISPLAY INVISIBLE (-5450 3125);
FORCEPROP 1 LAST PATH I62
J 0
(-5777 3250);
DISPLAY 0.872340 (-5777 3250);
PAINT GREEN (-5777 3250);
DISPLAY INVISIBLE (-5777 3250);
FORCEADD TAP..1
(-5775 3050);
FORCEPROP 3 LASTPIN (-5825 3050) SIG_NAME M_G_CPU1_SB_DQ<18>
J 0
(-5815 3060);
DISPLAY 0.659574 (-5815 3060);
PAINT MONO (-5815 3060);
DISPLAY INVISIBLE (-5815 3060);
FORCEPROP 1 LASTPIN (-5825 3050) BN 18
J 0
(-5837 3058);
DISPLAY 0.489362 (-5837 3058);
PAINT GREEN (-5837 3058);
FORCEPROP 2 LAST CDS_LIB mstr_standard
J 0
(-5775 3050);
DISPLAY 0.723404 (-5775 3050);
PAINT MONO (-5775 3050);
DISPLAY INVISIBLE (-5775 3050);
FORCEPROP 1 LAST BODY_TYPE PLUMBING
J 0
(-5775 3100);
DISPLAY 0.872340 (-5775 3100);
PAINT GREEN (-5775 3100);
DISPLAY INVISIBLE (-5775 3100);
FORCEPROP 1 LAST HDL_TAP TRUE
J 0
(-5450 2925);
DISPLAY 0.872340 (-5450 2925);
DISPLAY INVISIBLE (-5450 2925);
FORCEPROP 1 LAST PATH I63
J 0
(-5777 3050);
DISPLAY 0.872340 (-5777 3050);
PAINT GREEN (-5777 3050);
DISPLAY INVISIBLE (-5777 3050);
FORCEADD TAP..1
(-5775 3100);
FORCEPROP 3 LASTPIN (-5825 3100) SIG_NAME M_G_CPU1_SB_DQ<19>
J 0
(-5815 3110);
DISPLAY 0.659574 (-5815 3110);
PAINT MONO (-5815 3110);
DISPLAY INVISIBLE (-5815 3110);
FORCEPROP 1 LASTPIN (-5825 3100) BN 19
J 0
(-5837 3108);
DISPLAY 0.489362 (-5837 3108);
PAINT GREEN (-5837 3108);
FORCEPROP 2 LAST CDS_LIB mstr_standard
J 0
(-5775 3100);
DISPLAY 0.723404 (-5775 3100);
PAINT MONO (-5775 3100);
DISPLAY INVISIBLE (-5775 3100);
FORCEPROP 1 LAST BODY_TYPE PLUMBING
J 0
(-5775 3150);
DISPLAY 0.872340 (-5775 3150);
PAINT GREEN (-5775 3150);
DISPLAY INVISIBLE (-5775 3150);
FORCEPROP 1 LAST HDL_TAP TRUE
J 0
(-5450 2975);
DISPLAY 0.872340 (-5450 2975);
DISPLAY INVISIBLE (-5450 2975);
FORCEPROP 1 LAST PATH I64
J 0
(-5777 3100);
DISPLAY 0.872340 (-5777 3100);
PAINT GREEN (-5777 3100);
DISPLAY INVISIBLE (-5777 3100);
FORCEADD TAP..1
(-5775 3400);
FORCEPROP 3 LASTPIN (-5825 3400) SIG_NAME M_G_CPU1_SB_DQ<25>
J 0
(-5815 3410);
DISPLAY 0.659574 (-5815 3410);
PAINT MONO (-5815 3410);
DISPLAY INVISIBLE (-5815 3410);
FORCEPROP 1 LASTPIN (-5825 3400) BN 25
J 0
(-5837 3408);
DISPLAY 0.489362 (-5837 3408);
PAINT GREEN (-5837 3408);
FORCEPROP 2 LAST CDS_LIB mstr_standard
J 0
(-5775 3400);
DISPLAY 0.723404 (-5775 3400);
PAINT MONO (-5775 3400);
DISPLAY INVISIBLE (-5775 3400);
FORCEPROP 1 LAST BODY_TYPE PLUMBING
J 0
(-5775 3450);
DISPLAY 0.872340 (-5775 3450);
PAINT GREEN (-5775 3450);
DISPLAY INVISIBLE (-5775 3450);
FORCEPROP 1 LAST HDL_TAP TRUE
J 0
(-5450 3275);
DISPLAY 0.872340 (-5450 3275);
DISPLAY INVISIBLE (-5450 3275);
FORCEPROP 1 LAST PATH I65
J 0
(-5777 3400);
DISPLAY 0.872340 (-5777 3400);
PAINT GREEN (-5777 3400);
DISPLAY INVISIBLE (-5777 3400);
FORCEADD TAP..1
(-5775 3450);
FORCEPROP 3 LASTPIN (-5825 3450) SIG_NAME M_G_CPU1_SB_DQ<26>
J 0
(-5815 3460);
DISPLAY 0.659574 (-5815 3460);
PAINT MONO (-5815 3460);
DISPLAY INVISIBLE (-5815 3460);
FORCEPROP 1 LASTPIN (-5825 3450) BN 26
J 0
(-5837 3458);
DISPLAY 0.489362 (-5837 3458);
PAINT GREEN (-5837 3458);
FORCEPROP 2 LAST CDS_LIB mstr_standard
J 0
(-5775 3450);
DISPLAY 0.723404 (-5775 3450);
PAINT MONO (-5775 3450);
DISPLAY INVISIBLE (-5775 3450);
FORCEPROP 1 LAST BODY_TYPE PLUMBING
J 0
(-5775 3500);
DISPLAY 0.872340 (-5775 3500);
PAINT GREEN (-5775 3500);
DISPLAY INVISIBLE (-5775 3500);
FORCEPROP 1 LAST HDL_TAP TRUE
J 0
(-5450 3325);
DISPLAY 0.872340 (-5450 3325);
DISPLAY INVISIBLE (-5450 3325);
FORCEPROP 1 LAST PATH I66
J 0
(-5777 3450);
DISPLAY 0.872340 (-5777 3450);
PAINT GREEN (-5777 3450);
DISPLAY INVISIBLE (-5777 3450);
FORCEADD TAP..1
(-5775 3500);
FORCEPROP 3 LASTPIN (-5825 3500) SIG_NAME M_G_CPU1_SB_DQ<27>
J 0
(-5815 3510);
DISPLAY 0.659574 (-5815 3510);
PAINT MONO (-5815 3510);
DISPLAY INVISIBLE (-5815 3510);
FORCEPROP 1 LASTPIN (-5825 3500) BN 27
J 0
(-5837 3508);
DISPLAY 0.489362 (-5837 3508);
PAINT GREEN (-5837 3508);
FORCEPROP 2 LAST CDS_LIB mstr_standard
J 0
(-5775 3500);
DISPLAY 0.723404 (-5775 3500);
PAINT MONO (-5775 3500);
DISPLAY INVISIBLE (-5775 3500);
FORCEPROP 1 LAST BODY_TYPE PLUMBING
J 0
(-5775 3550);
DISPLAY 0.872340 (-5775 3550);
PAINT GREEN (-5775 3550);
DISPLAY INVISIBLE (-5775 3550);
FORCEPROP 1 LAST HDL_TAP TRUE
J 0
(-5450 3375);
DISPLAY 0.872340 (-5450 3375);
DISPLAY INVISIBLE (-5450 3375);
FORCEPROP 1 LAST PATH I67
J 0
(-5777 3500);
DISPLAY 0.872340 (-5777 3500);
PAINT GREEN (-5777 3500);
DISPLAY INVISIBLE (-5777 3500);
FORCEADD TAP..1
(-5775 3300);
FORCEPROP 3 LASTPIN (-5825 3300) SIG_NAME M_G_CPU1_SB_DQ<23>
J 0
(-5815 3310);
DISPLAY 0.659574 (-5815 3310);
PAINT MONO (-5815 3310);
DISPLAY INVISIBLE (-5815 3310);
FORCEPROP 1 LASTPIN (-5825 3300) BN 23
J 0
(-5837 3308);
DISPLAY 0.489362 (-5837 3308);
PAINT GREEN (-5837 3308);
FORCEPROP 2 LAST CDS_LIB mstr_standard
J 0
(-5775 3300);
DISPLAY 0.723404 (-5775 3300);
PAINT MONO (-5775 3300);
DISPLAY INVISIBLE (-5775 3300);
FORCEPROP 1 LAST BODY_TYPE PLUMBING
J 0
(-5775 3350);
DISPLAY 0.872340 (-5775 3350);
PAINT GREEN (-5775 3350);
DISPLAY INVISIBLE (-5775 3350);
FORCEPROP 1 LAST HDL_TAP TRUE
J 0
(-5450 3175);
DISPLAY 0.872340 (-5450 3175);
DISPLAY INVISIBLE (-5450 3175);
FORCEPROP 1 LAST PATH I68
J 0
(-5777 3300);
DISPLAY 0.872340 (-5777 3300);
PAINT GREEN (-5777 3300);
DISPLAY INVISIBLE (-5777 3300);
FORCEADD TAP..1
(-5775 3350);
FORCEPROP 3 LASTPIN (-5825 3350) SIG_NAME M_G_CPU1_SB_DQ<24>
J 0
(-5815 3360);
DISPLAY 0.659574 (-5815 3360);
PAINT MONO (-5815 3360);
DISPLAY INVISIBLE (-5815 3360);
FORCEPROP 1 LASTPIN (-5825 3350) BN 24
J 0
(-5837 3358);
DISPLAY 0.489362 (-5837 3358);
PAINT GREEN (-5837 3358);
FORCEPROP 2 LAST CDS_LIB mstr_standard
J 0
(-5775 3350);
DISPLAY 0.723404 (-5775 3350);
PAINT MONO (-5775 3350);
DISPLAY INVISIBLE (-5775 3350);
FORCEPROP 1 LAST BODY_TYPE PLUMBING
J 0
(-5775 3400);
DISPLAY 0.872340 (-5775 3400);
PAINT GREEN (-5775 3400);
DISPLAY INVISIBLE (-5775 3400);
FORCEPROP 1 LAST HDL_TAP TRUE
J 0
(-5450 3225);
DISPLAY 0.872340 (-5450 3225);
DISPLAY INVISIBLE (-5450 3225);
FORCEPROP 1 LAST PATH I69
J 0
(-5777 3350);
DISPLAY 0.872340 (-5777 3350);
PAINT GREEN (-5777 3350);
DISPLAY INVISIBLE (-5777 3350);
FORCEADD OFFPAGE..5
(-8075 3000);
FORCEPROP 2 LAST $XR0 43 
J 0
(-8329 3000);
DISPLAY 0.638298 (-8329 3000);
PAINT MONO (-8329 3000);
FORCEPROP 2 LAST PATH I7
J 0
(-8325 3050);
DISPLAY 1.021277 (-8325 3050);
DISPLAY INVISIBLE (-8325 3050);
FORCEPROP 1 LAST COMMENT_BODY TRUE
J 0
(-7975 2925);
DISPLAY 0.872340 (-7975 2925);
PAINT GREEN (-7975 2925);
DISPLAY INVISIBLE (-7975 2925);
FORCEPROP 1 LAST OFFPAGE TRUE
J 0
(-7750 2875);
DISPLAY 0.872340 (-7750 2875);
PAINT GREEN (-7750 2875);
DISPLAY INVISIBLE (-7750 2875);
FORCEPROP 2 LAST CDS_LIB mstr_standard
J 0
(-8075 3000);
DISPLAY INVISIBLE (-8075 3000);
FORCEADD TAP..1
(-5775 3650);
FORCEPROP 3 LASTPIN (-5825 3650) SIG_NAME M_G_CPU1_SB_DQ<30>
J 0
(-5815 3660);
DISPLAY 0.659574 (-5815 3660);
PAINT MONO (-5815 3660);
DISPLAY INVISIBLE (-5815 3660);
FORCEPROP 1 LASTPIN (-5825 3650) BN 30
J 0
(-5837 3658);
DISPLAY 0.489362 (-5837 3658);
PAINT GREEN (-5837 3658);
FORCEPROP 2 LAST CDS_LIB mstr_standard
J 0
(-5775 3650);
DISPLAY 0.723404 (-5775 3650);
PAINT MONO (-5775 3650);
DISPLAY INVISIBLE (-5775 3650);
FORCEPROP 1 LAST BODY_TYPE PLUMBING
J 0
(-5775 3700);
DISPLAY 0.872340 (-5775 3700);
PAINT GREEN (-5775 3700);
DISPLAY INVISIBLE (-5775 3700);
FORCEPROP 1 LAST HDL_TAP TRUE
J 0
(-5450 3525);
DISPLAY 0.872340 (-5450 3525);
DISPLAY INVISIBLE (-5450 3525);
FORCEPROP 1 LAST PATH I70
J 0
(-5777 3650);
DISPLAY 0.872340 (-5777 3650);
PAINT GREEN (-5777 3650);
DISPLAY INVISIBLE (-5777 3650);
FORCEADD TAP..1
(-5775 3700);
FORCEPROP 3 LASTPIN (-5825 3700) SIG_NAME M_G_CPU1_SB_DQ<31>
J 0
(-5815 3710);
DISPLAY 0.659574 (-5815 3710);
PAINT MONO (-5815 3710);
DISPLAY INVISIBLE (-5815 3710);
FORCEPROP 1 LASTPIN (-5825 3700) BN 31
J 0
(-5837 3708);
DISPLAY 0.489362 (-5837 3708);
PAINT GREEN (-5837 3708);
FORCEPROP 2 LAST CDS_LIB mstr_standard
J 0
(-5775 3700);
DISPLAY 0.723404 (-5775 3700);
PAINT MONO (-5775 3700);
DISPLAY INVISIBLE (-5775 3700);
FORCEPROP 1 LAST BODY_TYPE PLUMBING
J 0
(-5775 3750);
DISPLAY 0.872340 (-5775 3750);
PAINT GREEN (-5775 3750);
DISPLAY INVISIBLE (-5775 3750);
FORCEPROP 1 LAST HDL_TAP TRUE
J 0
(-5450 3575);
DISPLAY 0.872340 (-5450 3575);
DISPLAY INVISIBLE (-5450 3575);
FORCEPROP 1 LAST PATH I71
J 0
(-5777 3700);
DISPLAY 0.872340 (-5777 3700);
PAINT GREEN (-5777 3700);
DISPLAY INVISIBLE (-5777 3700);
FORCEADD TAP..1
(-5775 3550);
FORCEPROP 3 LASTPIN (-5825 3550) SIG_NAME M_G_CPU1_SB_DQ<28>
J 0
(-5815 3560);
DISPLAY 0.659574 (-5815 3560);
PAINT MONO (-5815 3560);
DISPLAY INVISIBLE (-5815 3560);
FORCEPROP 1 LASTPIN (-5825 3550) BN 28
J 0
(-5837 3558);
DISPLAY 0.489362 (-5837 3558);
PAINT GREEN (-5837 3558);
FORCEPROP 2 LAST CDS_LIB mstr_standard
J 0
(-5775 3550);
DISPLAY 0.723404 (-5775 3550);
PAINT MONO (-5775 3550);
DISPLAY INVISIBLE (-5775 3550);
FORCEPROP 1 LAST BODY_TYPE PLUMBING
J 0
(-5775 3600);
DISPLAY 0.872340 (-5775 3600);
PAINT GREEN (-5775 3600);
DISPLAY INVISIBLE (-5775 3600);
FORCEPROP 1 LAST HDL_TAP TRUE
J 0
(-5450 3425);
DISPLAY 0.872340 (-5450 3425);
DISPLAY INVISIBLE (-5450 3425);
FORCEPROP 1 LAST PATH I72
J 0
(-5777 3550);
DISPLAY 0.872340 (-5777 3550);
PAINT GREEN (-5777 3550);
DISPLAY INVISIBLE (-5777 3550);
FORCEADD TAP..1
(-5775 3600);
FORCEPROP 3 LASTPIN (-5825 3600) SIG_NAME M_G_CPU1_SB_DQ<29>
J 0
(-5815 3610);
DISPLAY 0.659574 (-5815 3610);
PAINT MONO (-5815 3610);
DISPLAY INVISIBLE (-5815 3610);
FORCEPROP 1 LASTPIN (-5825 3600) BN 29
J 0
(-5837 3608);
DISPLAY 0.489362 (-5837 3608);
PAINT GREEN (-5837 3608);
FORCEPROP 2 LAST CDS_LIB mstr_standard
J 0
(-5775 3600);
DISPLAY 0.723404 (-5775 3600);
PAINT MONO (-5775 3600);
DISPLAY INVISIBLE (-5775 3600);
FORCEPROP 1 LAST BODY_TYPE PLUMBING
J 0
(-5775 3650);
DISPLAY 0.872340 (-5775 3650);
PAINT GREEN (-5775 3650);
DISPLAY INVISIBLE (-5775 3650);
FORCEPROP 1 LAST HDL_TAP TRUE
J 0
(-5450 3475);
DISPLAY 0.872340 (-5450 3475);
DISPLAY INVISIBLE (-5450 3475);
FORCEPROP 1 LAST PATH I73
J 0
(-5777 3600);
DISPLAY 0.872340 (-5777 3600);
PAINT GREEN (-5777 3600);
DISPLAY INVISIBLE (-5777 3600);
FORCEADD OFFPAGE..3
(-5175 3750);
FORCEPROP 2 LAST $XR0 43 
J 0
(-4961 3750);
DISPLAY 0.638298 (-4961 3750);
PAINT MONO (-4961 3750);
FORCEPROP 2 LAST PATH I74
J 0
(-4850 3800);
DISPLAY 1.021277 (-4850 3800);
DISPLAY INVISIBLE (-4850 3800);
FORCEPROP 1 LAST COMMENT_BODY TRUE
J 0
(-5225 3650);
DISPLAY 0.872340 (-5225 3650);
PAINT GREEN (-5225 3650);
DISPLAY INVISIBLE (-5225 3650);
FORCEPROP 1 LAST OFFPAGE TRUE
J 0
(-4850 3625);
DISPLAY 0.872340 (-4850 3625);
PAINT GREEN (-4850 3625);
DISPLAY INVISIBLE (-4850 3625);
FORCEPROP 2 LAST CDS_LIB mstr_standard
J 0
(-5175 3750);
DISPLAY 0.723404 (-5175 3750);
PAINT MONO (-5175 3750);
DISPLAY INVISIBLE (-5175 3750);
FORCEADD TAP..1
R 2
(-7475 3800);
FORCEPROP 3 LASTPIN (-7425 3800) SIG_NAME M_G_CPU1_SA_CB<4>
J 0
(-7415 3810);
DISPLAY 0.659574 (-7415 3810);
PAINT MONO (-7415 3810);
DISPLAY INVISIBLE (-7415 3810);
FORCEPROP 1 LASTPIN (-7425 3800) BN 4
J 2
(-7413 3808);
DISPLAY 0.489362 (-7413 3808);
PAINT GREEN (-7413 3808);
FORCEPROP 2 LAST CDS_LIB mstr_standard
J 0
(-7475 3800);
DISPLAY 0.723404 (-7475 3800);
PAINT MONO (-7475 3800);
DISPLAY INVISIBLE (-7475 3800);
FORCEPROP 1 LAST BODY_TYPE PLUMBING
J 2
(-7475 3850);
DISPLAY 0.872340 (-7475 3850);
PAINT GREEN (-7475 3850);
DISPLAY INVISIBLE (-7475 3850);
FORCEPROP 1 LAST HDL_TAP TRUE
J 2
(-7800 3675);
DISPLAY 0.872340 (-7800 3675);
DISPLAY INVISIBLE (-7800 3675);
FORCEPROP 1 LAST PATH I76
J 2
(-7473 3800);
DISPLAY 0.872340 (-7473 3800);
PAINT GREEN (-7473 3800);
DISPLAY INVISIBLE (-7473 3800);
FORCEADD TAP..1
R 2
(-7475 3850);
FORCEPROP 3 LASTPIN (-7425 3850) SIG_NAME M_G_CPU1_SA_CB<5>
J 0
(-7415 3860);
DISPLAY 0.659574 (-7415 3860);
PAINT MONO (-7415 3860);
DISPLAY INVISIBLE (-7415 3860);
FORCEPROP 1 LASTPIN (-7425 3850) BN 5
J 2
(-7413 3858);
DISPLAY 0.489362 (-7413 3858);
PAINT GREEN (-7413 3858);
FORCEPROP 2 LAST CDS_LIB mstr_standard
J 0
(-7475 3850);
DISPLAY 0.723404 (-7475 3850);
PAINT MONO (-7475 3850);
DISPLAY INVISIBLE (-7475 3850);
FORCEPROP 1 LAST BODY_TYPE PLUMBING
J 2
(-7475 3900);
DISPLAY 0.872340 (-7475 3900);
PAINT GREEN (-7475 3900);
DISPLAY INVISIBLE (-7475 3900);
FORCEPROP 1 LAST HDL_TAP TRUE
J 2
(-7800 3725);
DISPLAY 0.872340 (-7800 3725);
DISPLAY INVISIBLE (-7800 3725);
FORCEPROP 1 LAST PATH I77
J 2
(-7473 3850);
DISPLAY 0.872340 (-7473 3850);
PAINT GREEN (-7473 3850);
DISPLAY INVISIBLE (-7473 3850);
FORCEADD TAP..1
R 2
(-7475 3900);
FORCEPROP 3 LASTPIN (-7425 3900) SIG_NAME M_G_CPU1_SA_CB<6>
J 0
(-7415 3910);
DISPLAY 0.659574 (-7415 3910);
PAINT MONO (-7415 3910);
DISPLAY INVISIBLE (-7415 3910);
FORCEPROP 1 LASTPIN (-7425 3900) BN 6
J 2
(-7413 3908);
DISPLAY 0.489362 (-7413 3908);
PAINT GREEN (-7413 3908);
FORCEPROP 2 LAST CDS_LIB mstr_standard
J 0
(-7475 3900);
DISPLAY 0.723404 (-7475 3900);
PAINT MONO (-7475 3900);
DISPLAY INVISIBLE (-7475 3900);
FORCEPROP 1 LAST BODY_TYPE PLUMBING
J 2
(-7475 3950);
DISPLAY 0.872340 (-7475 3950);
PAINT GREEN (-7475 3950);
DISPLAY INVISIBLE (-7475 3950);
FORCEPROP 1 LAST HDL_TAP TRUE
J 2
(-7800 3775);
DISPLAY 0.872340 (-7800 3775);
DISPLAY INVISIBLE (-7800 3775);
FORCEPROP 1 LAST PATH I78
J 2
(-7473 3900);
DISPLAY 0.872340 (-7473 3900);
PAINT GREEN (-7473 3900);
DISPLAY INVISIBLE (-7473 3900);
FORCEADD TAP..1
R 2
(-7475 3950);
FORCEPROP 3 LASTPIN (-7425 3950) SIG_NAME M_G_CPU1_SA_CB<7>
J 0
(-7415 3960);
DISPLAY 0.659574 (-7415 3960);
PAINT MONO (-7415 3960);
DISPLAY INVISIBLE (-7415 3960);
FORCEPROP 1 LASTPIN (-7425 3950) BN 7
J 2
(-7413 3958);
DISPLAY 0.489362 (-7413 3958);
PAINT GREEN (-7413 3958);
FORCEPROP 2 LAST CDS_LIB mstr_standard
J 0
(-7475 3950);
DISPLAY 0.723404 (-7475 3950);
PAINT MONO (-7475 3950);
DISPLAY INVISIBLE (-7475 3950);
FORCEPROP 1 LAST BODY_TYPE PLUMBING
J 2
(-7475 4000);
DISPLAY 0.872340 (-7475 4000);
PAINT GREEN (-7475 4000);
DISPLAY INVISIBLE (-7475 4000);
FORCEPROP 1 LAST HDL_TAP TRUE
J 2
(-7800 3825);
DISPLAY 0.872340 (-7800 3825);
DISPLAY INVISIBLE (-7800 3825);
FORCEPROP 1 LAST PATH I79
J 2
(-7473 3950);
DISPLAY 0.872340 (-7473 3950);
PAINT GREEN (-7473 3950);
DISPLAY INVISIBLE (-7473 3950);
FORCEADD OFFPAGE..1
(-8075 2850);
FORCEPROP 2 LAST $XR0 103 
J 0
(-8327 2850);
DISPLAY 0.638298 (-8327 2850);
PAINT MONO (-8327 2850);
FORCEPROP 2 LAST PATH I8
J 0
(-8350 2900);
DISPLAY 1.021277 (-8350 2900);
DISPLAY INVISIBLE (-8350 2900);
FORCEPROP 1 LAST COMMENT_BODY TRUE
J 0
(-7950 2750);
DISPLAY 0.872340 (-7950 2750);
PAINT GREEN (-7950 2750);
DISPLAY INVISIBLE (-7950 2750);
FORCEPROP 1 LAST OFFPAGE TRUE
J 0
(-7750 2725);
DISPLAY 0.872340 (-7750 2725);
PAINT GREEN (-7750 2725);
DISPLAY INVISIBLE (-7750 2725);
FORCEPROP 2 LAST CDS_LIB mstr_standard
J 0
(-8075 2850);
DISPLAY 0.808511 (-8075 2850);
DISPLAY INVISIBLE (-8075 2850);
FORCEADD TAP..1
R 2
(-7475 4750);
FORCEPROP 3 LASTPIN (-7425 4750) SIG_NAME M_G_CPU1_SB_CA<2>
J 0
(-7415 4760);
DISPLAY 0.659574 (-7415 4760);
PAINT MONO (-7415 4760);
DISPLAY INVISIBLE (-7415 4760);
FORCEPROP 1 LASTPIN (-7425 4750) BN 2
J 2
(-7413 4758);
DISPLAY 0.489362 (-7413 4758);
PAINT GREEN (-7413 4758);
FORCEPROP 2 LAST CDS_LIB mstr_standard
J 0
(-7475 4750);
DISPLAY 0.723404 (-7475 4750);
PAINT MONO (-7475 4750);
DISPLAY INVISIBLE (-7475 4750);
FORCEPROP 1 LAST BODY_TYPE PLUMBING
J 2
(-7475 4800);
DISPLAY 0.872340 (-7475 4800);
PAINT GREEN (-7475 4800);
DISPLAY INVISIBLE (-7475 4800);
FORCEPROP 1 LAST HDL_TAP TRUE
J 2
(-7800 4625);
DISPLAY 0.872340 (-7800 4625);
DISPLAY INVISIBLE (-7800 4625);
FORCEPROP 1 LAST PATH I80
J 2
(-7473 4750);
DISPLAY 0.872340 (-7473 4750);
PAINT GREEN (-7473 4750);
DISPLAY INVISIBLE (-7473 4750);
FORCEADD TAP..1
R 2
(-7475 4700);
FORCEPROP 3 LASTPIN (-7425 4700) SIG_NAME M_G_CPU1_SB_CA<1>
J 0
(-7415 4710);
DISPLAY 0.659574 (-7415 4710);
PAINT MONO (-7415 4710);
DISPLAY INVISIBLE (-7415 4710);
FORCEPROP 1 LASTPIN (-7425 4700) BN 1
J 2
(-7413 4708);
DISPLAY 0.489362 (-7413 4708);
PAINT GREEN (-7413 4708);
FORCEPROP 2 LAST CDS_LIB mstr_standard
J 0
(-7475 4700);
DISPLAY 0.723404 (-7475 4700);
PAINT MONO (-7475 4700);
DISPLAY INVISIBLE (-7475 4700);
FORCEPROP 1 LAST BODY_TYPE PLUMBING
J 2
(-7475 4750);
DISPLAY 0.872340 (-7475 4750);
PAINT GREEN (-7475 4750);
DISPLAY INVISIBLE (-7475 4750);
FORCEPROP 1 LAST HDL_TAP TRUE
J 2
(-7800 4575);
DISPLAY 0.872340 (-7800 4575);
DISPLAY INVISIBLE (-7800 4575);
FORCEPROP 1 LAST PATH I81
J 2
(-7473 4700);
DISPLAY 0.872340 (-7473 4700);
PAINT GREEN (-7473 4700);
DISPLAY INVISIBLE (-7473 4700);
FORCEADD TAP..1
R 2
(-7475 4650);
FORCEPROP 3 LASTPIN (-7425 4650) SIG_NAME M_G_CPU1_SB_CA<0>
J 0
(-7415 4660);
DISPLAY 0.659574 (-7415 4660);
PAINT MONO (-7415 4660);
DISPLAY INVISIBLE (-7415 4660);
FORCEPROP 1 LASTPIN (-7425 4650) BN 0
J 2
(-7413 4658);
DISPLAY 0.489362 (-7413 4658);
PAINT GREEN (-7413 4658);
FORCEPROP 2 LAST CDS_LIB mstr_standard
J 0
(-7475 4650);
DISPLAY 0.723404 (-7475 4650);
PAINT MONO (-7475 4650);
DISPLAY INVISIBLE (-7475 4650);
FORCEPROP 1 LAST BODY_TYPE PLUMBING
J 2
(-7475 4700);
DISPLAY 0.872340 (-7475 4700);
PAINT GREEN (-7475 4700);
DISPLAY INVISIBLE (-7475 4700);
FORCEPROP 1 LAST HDL_TAP TRUE
J 2
(-7800 4525);
DISPLAY 0.872340 (-7800 4525);
DISPLAY INVISIBLE (-7800 4525);
FORCEPROP 1 LAST PATH I82
J 2
(-7473 4650);
DISPLAY 0.872340 (-7473 4650);
PAINT GREEN (-7473 4650);
DISPLAY INVISIBLE (-7473 4650);
FORCEADD TAP..1
R 2
(-7475 4850);
FORCEPROP 3 LASTPIN (-7425 4850) SIG_NAME M_G_CPU1_SB_CA<4>
J 0
(-7415 4860);
DISPLAY 0.659574 (-7415 4860);
PAINT MONO (-7415 4860);
DISPLAY INVISIBLE (-7415 4860);
FORCEPROP 1 LASTPIN (-7425 4850) BN 4
J 2
(-7413 4858);
DISPLAY 0.489362 (-7413 4858);
PAINT GREEN (-7413 4858);
FORCEPROP 2 LAST CDS_LIB mstr_standard
J 0
(-7475 4850);
DISPLAY 0.723404 (-7475 4850);
PAINT MONO (-7475 4850);
DISPLAY INVISIBLE (-7475 4850);
FORCEPROP 1 LAST BODY_TYPE PLUMBING
J 2
(-7475 4900);
DISPLAY 0.872340 (-7475 4900);
PAINT GREEN (-7475 4900);
DISPLAY INVISIBLE (-7475 4900);
FORCEPROP 1 LAST HDL_TAP TRUE
J 2
(-7800 4725);
DISPLAY 0.872340 (-7800 4725);
DISPLAY INVISIBLE (-7800 4725);
FORCEPROP 1 LAST PATH I83
J 2
(-7473 4850);
DISPLAY 0.872340 (-7473 4850);
PAINT GREEN (-7473 4850);
DISPLAY INVISIBLE (-7473 4850);
FORCEADD TAP..1
R 2
(-7475 4800);
FORCEPROP 3 LASTPIN (-7425 4800) SIG_NAME M_G_CPU1_SB_CA<3>
J 0
(-7415 4810);
DISPLAY 0.659574 (-7415 4810);
PAINT MONO (-7415 4810);
DISPLAY INVISIBLE (-7415 4810);
FORCEPROP 1 LASTPIN (-7425 4800) BN 3
J 2
(-7413 4808);
DISPLAY 0.489362 (-7413 4808);
PAINT GREEN (-7413 4808);
FORCEPROP 2 LAST CDS_LIB mstr_standard
J 0
(-7475 4800);
DISPLAY 0.723404 (-7475 4800);
PAINT MONO (-7475 4800);
DISPLAY INVISIBLE (-7475 4800);
FORCEPROP 1 LAST BODY_TYPE PLUMBING
J 2
(-7475 4850);
DISPLAY 0.872340 (-7475 4850);
PAINT GREEN (-7475 4850);
DISPLAY INVISIBLE (-7475 4850);
FORCEPROP 1 LAST HDL_TAP TRUE
J 2
(-7800 4675);
DISPLAY 0.872340 (-7800 4675);
DISPLAY INVISIBLE (-7800 4675);
FORCEPROP 1 LAST PATH I84
J 2
(-7473 4800);
DISPLAY 0.872340 (-7473 4800);
PAINT GREEN (-7473 4800);
DISPLAY INVISIBLE (-7473 4800);
FORCEADD TAP..1
R 2
(-7475 4950);
FORCEPROP 3 LASTPIN (-7425 4950) SIG_NAME M_G_CPU1_SB_CA<6>
J 0
(-7415 4960);
DISPLAY 0.659574 (-7415 4960);
PAINT MONO (-7415 4960);
DISPLAY INVISIBLE (-7415 4960);
FORCEPROP 1 LASTPIN (-7425 4950) BN 6
J 2
(-7413 4958);
DISPLAY 0.489362 (-7413 4958);
PAINT GREEN (-7413 4958);
FORCEPROP 2 LAST CDS_LIB mstr_standard
J 0
(-7475 4950);
DISPLAY 0.723404 (-7475 4950);
PAINT MONO (-7475 4950);
DISPLAY INVISIBLE (-7475 4950);
FORCEPROP 1 LAST BODY_TYPE PLUMBING
J 2
(-7475 5000);
DISPLAY 0.872340 (-7475 5000);
PAINT GREEN (-7475 5000);
DISPLAY INVISIBLE (-7475 5000);
FORCEPROP 1 LAST HDL_TAP TRUE
J 2
(-7800 4825);
DISPLAY 0.872340 (-7800 4825);
DISPLAY INVISIBLE (-7800 4825);
FORCEPROP 1 LAST PATH I85
J 2
(-7473 4950);
DISPLAY 0.872340 (-7473 4950);
PAINT GREEN (-7473 4950);
DISPLAY INVISIBLE (-7473 4950);
FORCEADD TAP..1
R 2
(-7475 4900);
FORCEPROP 3 LASTPIN (-7425 4900) SIG_NAME M_G_CPU1_SB_CA<5>
J 0
(-7415 4910);
DISPLAY 0.659574 (-7415 4910);
PAINT MONO (-7415 4910);
DISPLAY INVISIBLE (-7415 4910);
FORCEPROP 1 LASTPIN (-7425 4900) BN 5
J 2
(-7413 4908);
DISPLAY 0.489362 (-7413 4908);
PAINT GREEN (-7413 4908);
FORCEPROP 2 LAST CDS_LIB mstr_standard
J 0
(-7475 4900);
DISPLAY 0.723404 (-7475 4900);
PAINT MONO (-7475 4900);
DISPLAY INVISIBLE (-7475 4900);
FORCEPROP 1 LAST BODY_TYPE PLUMBING
J 2
(-7475 4950);
DISPLAY 0.872340 (-7475 4950);
PAINT GREEN (-7475 4950);
DISPLAY INVISIBLE (-7475 4950);
FORCEPROP 1 LAST HDL_TAP TRUE
J 2
(-7800 4775);
DISPLAY 0.872340 (-7800 4775);
DISPLAY INVISIBLE (-7800 4775);
FORCEPROP 1 LAST PATH I86
J 2
(-7473 4900);
DISPLAY 0.872340 (-7473 4900);
PAINT GREEN (-7473 4900);
DISPLAY INVISIBLE (-7473 4900);
FORCEADD TAP..1
R 2
(-7475 5050);
FORCEPROP 3 LASTPIN (-7425 5050) SIG_NAME M_G_CPU1_SA_CA<0>
J 0
(-7415 5060);
DISPLAY 0.659574 (-7415 5060);
PAINT MONO (-7415 5060);
DISPLAY INVISIBLE (-7415 5060);
FORCEPROP 1 LASTPIN (-7425 5050) BN 0
J 2
(-7413 5058);
DISPLAY 0.489362 (-7413 5058);
PAINT GREEN (-7413 5058);
FORCEPROP 2 LAST CDS_LIB mstr_standard
J 0
(-7475 5050);
DISPLAY 0.723404 (-7475 5050);
PAINT MONO (-7475 5050);
DISPLAY INVISIBLE (-7475 5050);
FORCEPROP 1 LAST BODY_TYPE PLUMBING
J 2
(-7475 5100);
DISPLAY 0.872340 (-7475 5100);
PAINT GREEN (-7475 5100);
DISPLAY INVISIBLE (-7475 5100);
FORCEPROP 1 LAST HDL_TAP TRUE
J 2
(-7800 4925);
DISPLAY 0.872340 (-7800 4925);
DISPLAY INVISIBLE (-7800 4925);
FORCEPROP 1 LAST PATH I87
J 2
(-7473 5050);
DISPLAY 0.872340 (-7473 5050);
PAINT GREEN (-7473 5050);
DISPLAY INVISIBLE (-7473 5050);
FORCEADD TAP..1
R 2
(-7475 5150);
FORCEPROP 3 LASTPIN (-7425 5150) SIG_NAME M_G_CPU1_SA_CA<2>
J 0
(-7415 5160);
DISPLAY 0.659574 (-7415 5160);
PAINT MONO (-7415 5160);
DISPLAY INVISIBLE (-7415 5160);
FORCEPROP 1 LASTPIN (-7425 5150) BN 2
J 2
(-7413 5158);
DISPLAY 0.489362 (-7413 5158);
PAINT GREEN (-7413 5158);
FORCEPROP 2 LAST CDS_LIB mstr_standard
J 0
(-7475 5150);
DISPLAY 0.723404 (-7475 5150);
PAINT MONO (-7475 5150);
DISPLAY INVISIBLE (-7475 5150);
FORCEPROP 1 LAST BODY_TYPE PLUMBING
J 2
(-7475 5200);
DISPLAY 0.872340 (-7475 5200);
PAINT GREEN (-7475 5200);
DISPLAY INVISIBLE (-7475 5200);
FORCEPROP 1 LAST HDL_TAP TRUE
J 2
(-7800 5025);
DISPLAY 0.872340 (-7800 5025);
DISPLAY INVISIBLE (-7800 5025);
FORCEPROP 1 LAST PATH I88
J 2
(-7473 5150);
DISPLAY 0.872340 (-7473 5150);
PAINT GREEN (-7473 5150);
DISPLAY INVISIBLE (-7473 5150);
FORCEADD TAP..1
R 2
(-7475 5100);
FORCEPROP 3 LASTPIN (-7425 5100) SIG_NAME M_G_CPU1_SA_CA<1>
J 0
(-7415 5110);
DISPLAY 0.659574 (-7415 5110);
PAINT MONO (-7415 5110);
DISPLAY INVISIBLE (-7415 5110);
FORCEPROP 1 LASTPIN (-7425 5100) BN 1
J 2
(-7413 5108);
DISPLAY 0.489362 (-7413 5108);
PAINT GREEN (-7413 5108);
FORCEPROP 2 LAST CDS_LIB mstr_standard
J 0
(-7475 5100);
DISPLAY 0.723404 (-7475 5100);
PAINT MONO (-7475 5100);
DISPLAY INVISIBLE (-7475 5100);
FORCEPROP 1 LAST BODY_TYPE PLUMBING
J 2
(-7475 5150);
DISPLAY 0.872340 (-7475 5150);
PAINT GREEN (-7475 5150);
DISPLAY INVISIBLE (-7475 5150);
FORCEPROP 1 LAST HDL_TAP TRUE
J 2
(-7800 4975);
DISPLAY 0.872340 (-7800 4975);
DISPLAY INVISIBLE (-7800 4975);
FORCEPROP 1 LAST PATH I89
J 2
(-7473 5100);
DISPLAY 0.872340 (-7473 5100);
PAINT GREEN (-7473 5100);
DISPLAY INVISIBLE (-7473 5100);
FORCEADD OFFPAGE..1
(-8075 3050);
FORCEPROP 2 LAST $XR0 43 
J 0
(-8296 3050);
DISPLAY 0.638298 (-8296 3050);
PAINT MONO (-8296 3050);
FORCEPROP 2 LAST PATH I9
J 0
(-8325 3100);
DISPLAY 1.021277 (-8325 3100);
DISPLAY INVISIBLE (-8325 3100);
FORCEPROP 1 LAST COMMENT_BODY TRUE
J 0
(-7950 2950);
DISPLAY 0.872340 (-7950 2950);
PAINT GREEN (-7950 2950);
DISPLAY INVISIBLE (-7950 2950);
FORCEPROP 1 LAST OFFPAGE TRUE
J 0
(-7750 2925);
DISPLAY 0.872340 (-7750 2925);
PAINT GREEN (-7750 2925);
DISPLAY INVISIBLE (-7750 2925);
FORCEPROP 2 LAST CDS_LIB mstr_standard
J 0
(-8075 3050);
DISPLAY 0.808511 (-8075 3050);
DISPLAY INVISIBLE (-8075 3050);
FORCEADD TAP..1
R 2
(-7475 5200);
FORCEPROP 3 LASTPIN (-7425 5200) SIG_NAME M_G_CPU1_SA_CA<3>
J 0
(-7415 5210);
DISPLAY 0.659574 (-7415 5210);
PAINT MONO (-7415 5210);
DISPLAY INVISIBLE (-7415 5210);
FORCEPROP 1 LASTPIN (-7425 5200) BN 3
J 2
(-7413 5208);
DISPLAY 0.489362 (-7413 5208);
PAINT GREEN (-7413 5208);
FORCEPROP 2 LAST CDS_LIB mstr_standard
J 0
(-7475 5200);
DISPLAY 0.723404 (-7475 5200);
PAINT MONO (-7475 5200);
DISPLAY INVISIBLE (-7475 5200);
FORCEPROP 1 LAST BODY_TYPE PLUMBING
J 2
(-7475 5250);
DISPLAY 0.872340 (-7475 5250);
PAINT GREEN (-7475 5250);
DISPLAY INVISIBLE (-7475 5250);
FORCEPROP 1 LAST HDL_TAP TRUE
J 2
(-7800 5075);
DISPLAY 0.872340 (-7800 5075);
DISPLAY INVISIBLE (-7800 5075);
FORCEPROP 1 LAST PATH I90
J 2
(-7473 5200);
DISPLAY 0.872340 (-7473 5200);
PAINT GREEN (-7473 5200);
DISPLAY INVISIBLE (-7473 5200);
FORCEADD TAP..1
R 2
(-7475 5250);
FORCEPROP 3 LASTPIN (-7425 5250) SIG_NAME M_G_CPU1_SA_CA<4>
J 0
(-7415 5260);
DISPLAY 0.659574 (-7415 5260);
PAINT MONO (-7415 5260);
DISPLAY INVISIBLE (-7415 5260);
FORCEPROP 1 LASTPIN (-7425 5250) BN 4
J 2
(-7413 5258);
DISPLAY 0.489362 (-7413 5258);
PAINT GREEN (-7413 5258);
FORCEPROP 2 LAST CDS_LIB mstr_standard
J 0
(-7475 5250);
DISPLAY 0.723404 (-7475 5250);
PAINT MONO (-7475 5250);
DISPLAY INVISIBLE (-7475 5250);
FORCEPROP 1 LAST BODY_TYPE PLUMBING
J 2
(-7475 5300);
DISPLAY 0.872340 (-7475 5300);
PAINT GREEN (-7475 5300);
DISPLAY INVISIBLE (-7475 5300);
FORCEPROP 1 LAST HDL_TAP TRUE
J 2
(-7800 5125);
DISPLAY 0.872340 (-7800 5125);
DISPLAY INVISIBLE (-7800 5125);
FORCEPROP 1 LAST PATH I91
J 2
(-7473 5250);
DISPLAY 0.872340 (-7473 5250);
PAINT GREEN (-7473 5250);
DISPLAY INVISIBLE (-7473 5250);
FORCEADD TAP..1
R 2
(-7475 5300);
FORCEPROP 3 LASTPIN (-7425 5300) SIG_NAME M_G_CPU1_SA_CA<5>
J 0
(-7415 5310);
DISPLAY 0.659574 (-7415 5310);
PAINT MONO (-7415 5310);
DISPLAY INVISIBLE (-7415 5310);
FORCEPROP 1 LASTPIN (-7425 5300) BN 5
J 2
(-7413 5308);
DISPLAY 0.489362 (-7413 5308);
PAINT GREEN (-7413 5308);
FORCEPROP 2 LAST CDS_LIB mstr_standard
J 0
(-7475 5300);
DISPLAY 0.723404 (-7475 5300);
PAINT MONO (-7475 5300);
DISPLAY INVISIBLE (-7475 5300);
FORCEPROP 1 LAST BODY_TYPE PLUMBING
J 2
(-7475 5350);
DISPLAY 0.872340 (-7475 5350);
PAINT GREEN (-7475 5350);
DISPLAY INVISIBLE (-7475 5350);
FORCEPROP 1 LAST HDL_TAP TRUE
J 2
(-7800 5175);
DISPLAY 0.872340 (-7800 5175);
DISPLAY INVISIBLE (-7800 5175);
FORCEPROP 1 LAST PATH I92
J 2
(-7473 5300);
DISPLAY 0.872340 (-7473 5300);
PAINT GREEN (-7473 5300);
DISPLAY INVISIBLE (-7473 5300);
FORCEADD TAP..1
R 2
(-7475 5350);
FORCEPROP 3 LASTPIN (-7425 5350) SIG_NAME M_G_CPU1_SA_CA<6>
J 0
(-7415 5360);
DISPLAY 0.659574 (-7415 5360);
PAINT MONO (-7415 5360);
DISPLAY INVISIBLE (-7415 5360);
FORCEPROP 1 LASTPIN (-7425 5350) BN 6
J 2
(-7413 5358);
DISPLAY 0.489362 (-7413 5358);
PAINT GREEN (-7413 5358);
FORCEPROP 2 LAST CDS_LIB mstr_standard
J 0
(-7475 5350);
DISPLAY 0.723404 (-7475 5350);
PAINT MONO (-7475 5350);
DISPLAY INVISIBLE (-7475 5350);
FORCEPROP 1 LAST BODY_TYPE PLUMBING
J 2
(-7475 5400);
DISPLAY 0.872340 (-7475 5400);
PAINT GREEN (-7475 5400);
DISPLAY INVISIBLE (-7475 5400);
FORCEPROP 1 LAST HDL_TAP TRUE
J 2
(-7800 5225);
DISPLAY 0.872340 (-7800 5225);
DISPLAY INVISIBLE (-7800 5225);
FORCEPROP 1 LAST PATH I93
J 2
(-7473 5350);
DISPLAY 0.872340 (-7473 5350);
PAINT GREEN (-7473 5350);
DISPLAY INVISIBLE (-7473 5350);
FORCEADD TAP..1
(-5775 4000);
FORCEPROP 3 LASTPIN (-5825 4000) SIG_NAME M_G_CPU1_SA_DQ<4>
J 0
(-5815 4010);
DISPLAY 0.659574 (-5815 4010);
PAINT MONO (-5815 4010);
DISPLAY INVISIBLE (-5815 4010);
FORCEPROP 1 LASTPIN (-5825 4000) BN 4
J 0
(-5837 4008);
DISPLAY 0.489362 (-5837 4008);
PAINT GREEN (-5837 4008);
FORCEPROP 2 LAST CDS_LIB mstr_standard
J 0
(-5775 4000);
DISPLAY 0.723404 (-5775 4000);
PAINT MONO (-5775 4000);
DISPLAY INVISIBLE (-5775 4000);
FORCEPROP 1 LAST BODY_TYPE PLUMBING
J 0
(-5775 4050);
DISPLAY 0.872340 (-5775 4050);
PAINT GREEN (-5775 4050);
DISPLAY INVISIBLE (-5775 4050);
FORCEPROP 1 LAST HDL_TAP TRUE
J 0
(-5450 3875);
DISPLAY 0.872340 (-5450 3875);
DISPLAY INVISIBLE (-5450 3875);
FORCEPROP 1 LAST PATH I94
J 0
(-5777 4000);
DISPLAY 0.872340 (-5777 4000);
PAINT GREEN (-5777 4000);
DISPLAY INVISIBLE (-5777 4000);
FORCEADD TAP..1
(-5775 3900);
FORCEPROP 3 LASTPIN (-5825 3900) SIG_NAME M_G_CPU1_SA_DQ<2>
J 0
(-5815 3910);
DISPLAY 0.659574 (-5815 3910);
PAINT MONO (-5815 3910);
DISPLAY INVISIBLE (-5815 3910);
FORCEPROP 1 LASTPIN (-5825 3900) BN 2
J 0
(-5837 3908);
DISPLAY 0.489362 (-5837 3908);
PAINT GREEN (-5837 3908);
FORCEPROP 2 LAST CDS_LIB mstr_standard
J 0
(-5775 3900);
DISPLAY 0.723404 (-5775 3900);
PAINT MONO (-5775 3900);
DISPLAY INVISIBLE (-5775 3900);
FORCEPROP 1 LAST BODY_TYPE PLUMBING
J 0
(-5775 3950);
DISPLAY 0.872340 (-5775 3950);
PAINT GREEN (-5775 3950);
DISPLAY INVISIBLE (-5775 3950);
FORCEPROP 1 LAST HDL_TAP TRUE
J 0
(-5450 3775);
DISPLAY 0.872340 (-5450 3775);
DISPLAY INVISIBLE (-5450 3775);
FORCEPROP 1 LAST PATH I95
J 0
(-5777 3900);
DISPLAY 0.872340 (-5777 3900);
PAINT GREEN (-5777 3900);
DISPLAY INVISIBLE (-5777 3900);
FORCEADD TAP..1
(-5775 3950);
FORCEPROP 3 LASTPIN (-5825 3950) SIG_NAME M_G_CPU1_SA_DQ<3>
J 0
(-5815 3960);
DISPLAY 0.659574 (-5815 3960);
PAINT MONO (-5815 3960);
DISPLAY INVISIBLE (-5815 3960);
FORCEPROP 1 LASTPIN (-5825 3950) BN 3
J 0
(-5837 3958);
DISPLAY 0.489362 (-5837 3958);
PAINT GREEN (-5837 3958);
FORCEPROP 2 LAST CDS_LIB mstr_standard
J 0
(-5775 3950);
DISPLAY 0.723404 (-5775 3950);
PAINT MONO (-5775 3950);
DISPLAY INVISIBLE (-5775 3950);
FORCEPROP 1 LAST BODY_TYPE PLUMBING
J 0
(-5775 4000);
DISPLAY 0.872340 (-5775 4000);
PAINT GREEN (-5775 4000);
DISPLAY INVISIBLE (-5775 4000);
FORCEPROP 1 LAST HDL_TAP TRUE
J 0
(-5450 3825);
DISPLAY 0.872340 (-5450 3825);
DISPLAY INVISIBLE (-5450 3825);
FORCEPROP 1 LAST PATH I96
J 0
(-5777 3950);
DISPLAY 0.872340 (-5777 3950);
PAINT GREEN (-5777 3950);
DISPLAY INVISIBLE (-5777 3950);
FORCEADD TAP..1
(-5775 3800);
FORCEPROP 3 LASTPIN (-5825 3800) SIG_NAME M_G_CPU1_SA_DQ<0>
J 0
(-5815 3810);
DISPLAY 0.659574 (-5815 3810);
PAINT MONO (-5815 3810);
DISPLAY INVISIBLE (-5815 3810);
FORCEPROP 1 LASTPIN (-5825 3800) BN 0
J 0
(-5837 3808);
DISPLAY 0.489362 (-5837 3808);
PAINT GREEN (-5837 3808);
FORCEPROP 2 LAST CDS_LIB mstr_standard
J 0
(-5775 3800);
DISPLAY 0.723404 (-5775 3800);
PAINT MONO (-5775 3800);
DISPLAY INVISIBLE (-5775 3800);
FORCEPROP 1 LAST BODY_TYPE PLUMBING
J 0
(-5775 3850);
DISPLAY 0.872340 (-5775 3850);
PAINT GREEN (-5775 3850);
DISPLAY INVISIBLE (-5775 3850);
FORCEPROP 1 LAST HDL_TAP TRUE
J 0
(-5450 3675);
DISPLAY 0.872340 (-5450 3675);
DISPLAY INVISIBLE (-5450 3675);
FORCEPROP 1 LAST PATH I97
J 0
(-5777 3800);
DISPLAY 0.872340 (-5777 3800);
PAINT GREEN (-5777 3800);
DISPLAY INVISIBLE (-5777 3800);
FORCEADD TAP..1
(-5775 3850);
FORCEPROP 3 LASTPIN (-5825 3850) SIG_NAME M_G_CPU1_SA_DQ<1>
J 0
(-5815 3860);
DISPLAY 0.659574 (-5815 3860);
PAINT MONO (-5815 3860);
DISPLAY INVISIBLE (-5815 3860);
FORCEPROP 1 LASTPIN (-5825 3850) BN 1
J 0
(-5837 3858);
DISPLAY 0.489362 (-5837 3858);
PAINT GREEN (-5837 3858);
FORCEPROP 2 LAST CDS_LIB mstr_standard
J 0
(-5775 3850);
DISPLAY 0.723404 (-5775 3850);
PAINT MONO (-5775 3850);
DISPLAY INVISIBLE (-5775 3850);
FORCEPROP 1 LAST BODY_TYPE PLUMBING
J 0
(-5775 3900);
DISPLAY 0.872340 (-5775 3900);
PAINT GREEN (-5775 3900);
DISPLAY INVISIBLE (-5775 3900);
FORCEPROP 1 LAST HDL_TAP TRUE
J 0
(-5450 3725);
DISPLAY 0.872340 (-5450 3725);
DISPLAY INVISIBLE (-5450 3725);
FORCEPROP 1 LAST PATH I98
J 0
(-5777 3850);
DISPLAY 0.872340 (-5777 3850);
PAINT GREEN (-5777 3850);
DISPLAY INVISIBLE (-5777 3850);
FORCEADD TAP..1
(-5775 4150);
FORCEPROP 3 LASTPIN (-5825 4150) SIG_NAME M_G_CPU1_SA_DQ<7>
J 0
(-5815 4160);
DISPLAY 0.659574 (-5815 4160);
PAINT MONO (-5815 4160);
DISPLAY INVISIBLE (-5815 4160);
FORCEPROP 1 LASTPIN (-5825 4150) BN 7
J 0
(-5837 4158);
DISPLAY 0.489362 (-5837 4158);
PAINT GREEN (-5837 4158);
FORCEPROP 2 LAST CDS_LIB mstr_standard
J 0
(-5775 4150);
DISPLAY 0.723404 (-5775 4150);
PAINT MONO (-5775 4150);
DISPLAY INVISIBLE (-5775 4150);
FORCEPROP 1 LAST BODY_TYPE PLUMBING
J 0
(-5775 4200);
DISPLAY 0.872340 (-5775 4200);
PAINT GREEN (-5775 4200);
DISPLAY INVISIBLE (-5775 4200);
FORCEPROP 1 LAST HDL_TAP TRUE
J 0
(-5450 4025);
DISPLAY 0.872340 (-5450 4025);
DISPLAY INVISIBLE (-5450 4025);
FORCEPROP 1 LAST PATH I99
J 0
(-5777 4150);
DISPLAY 0.872340 (-5777 4150);
PAINT GREEN (-5777 4150);
DISPLAY INVISIBLE (-5777 4150);
FORCEADD QUANTA_TITLE_BLOCK_C..1
(0 0);
FORCEPROP 0 LAST CDS_CON_LAST_MODIFIED Fri Mar 11 14:53:06 2022
J 0
(-1885 15);
DISPLAY INVISIBLE (-1885 15);
FORCEPROP 1 LAST CUSTOM_TXT_CDS <CON_LAST_MODIFIED>
J 0
(-1885 15);
DISPLAY 0.978723 (-1885 15);
FORCEPROP 2 LAST CUSTOM_TXT_CDS <XR_PAGE_TITLE>
J 0
(-7890 5250);
DISPLAY 0.638298 (-7890 5250);
PAINT PINK (-7890 5250);
DISPLAY INVISIBLE (-7890 5250);
FORCEPROP 1 LAST CUSTOM_TXT_CDS <NAME_2>
J 0
(-3175 50);
FORCEPROP 1 LAST CUSTOM_TXT_CDS <NAME_1>
J 0
(-3175 175);
FORCEPROP 1 LAST CUSTOM_TXT_CDS <Q_NUMBER>
J 0
(-1403 103);
DISPLAY 1.212766 (-1403 103);
FORCEPROP 1 LAST CUSTOM_TXT_CDS <Q_PROJ>
J 0
(-2382 102);
DISPLAY 1.212766 (-2382 102);
FORCEPROP 1 LAST CUSTOM_TXT_CDS <Q_REV>
J 0
(-184 103);
DISPLAY 1.212766 (-184 103);
FORCEPROP 1 LAST CUSTOM_TXT_CDS <CON_PAGE_NUM> OF <CON_TOTAL_PAGES>
J 0
(-446 18);
DISPLAY 0.978723 (-446 18);
FORCEPROP 1 LAST Q_TITLE DDR5 - CPU1 CHG
J 0
(-9325 50);
DISPLAY 2.446809 (-9325 50);
PAINT GREEN (-9325 50);
FORCEPROP 1 LAST Q_DEPT BU9
J 1
(-3763 49);
DISPLAY 1.957447 (-3763 49);
PAINT GREEN (-3763 49);
FORCEPROP 2 LAST PAGE_BORDER TRUE
J 0
(-7890 5250);
DISPLAY 0.638298 (-7890 5250);
PAINT PINK (-7890 5250);
DISPLAY INVISIBLE (-7890 5250);
FORCEPROP 1 LAST CDS_LMAN_SYM_OUTLINE -9475,6775,100,-125
J 0
(0 0);
DISPLAY 0.468085 (0 0);
PAINT GREEN (0 0);
DISPLAY INVISIBLE (0 0);
FORCEPROP 2 LAST CDS_LIB pure_quanta
J 0
(0 0);
DISPLAY INVISIBLE (0 0);
FORCEPROP 1 LAST COMMENT_BODY TRUE
J 0
(12 -13);
DISPLAY 0.978723 (12 -13);
PAINT GREEN (12 -13);
DISPLAY INVISIBLE (12 -13);
FORCEPROP 2 LAST CDS_XR_PAGE_TITLE CR-103 : @T6G_MB_LIB.T6G(SCH_1):PAGE103
J 0
(-7890 5250);
DISPLAY 0.638298 (-7890 5250);
PAINT PINK (-7890 5250);
DISPLAY INVISIBLE (-7890 5250);
FORCEADD DNS..2
(-8250 2250);
PAINT RED (-8250 2250);
FORCEPROP 2 LAST CDS_LIB mstr_misc
J 0
(-8250 2250);
DISPLAY INVISIBLE (-8250 2250);
FORCEPROP 1 LAST COMMENT_BODY TRUE
R 1
J 0
(-8175 2025);
DISPLAY 0.872340 (-8175 2025);
PAINT PEACH (-8175 2025);
DISPLAY INVISIBLE (-8175 2025);
WIRE 17 -1 (-5725 5375)(-5725 5325);
WIRE 17 -1 (-5725 5400)(-5725 5375);
WIRE 17 -1 (-5725 5325)(-5725 5275);
WIRE 17 -1 (-5725 5275)(-5725 5225);
WIRE 17 -1 (-5725 5400)(-5225 5400);
FORCEPROP 2 LAST SIG_NAME M_G_CPU1_SA_DQ<31:0>
J 2
(-5225 5410);
DISPLAY 0.489362 (-5225 5410);
WIRE 17 -1 (-7525 3975)(-7525 3925);
WIRE 17 -1 (-7525 3975)(-7525 4000);
WIRE 17 -1 (-7525 3875)(-7525 3925);
WIRE 17 -1 (-7525 3875)(-7525 3825);
WIRE 17 -1 (-7525 4000)(-8025 4000);
FORCEPROP 2 LAST SIG_NAME M_G_CPU1_SA_CB<7:0>
J 0
(-8025 4010);
DISPLAY 0.489362 (-8025 4010);
WIRE 17 -1 (-7525 3775)(-7525 3825);
WIRE 17 -1 (-7525 3725)(-7525 3775);
WIRE 17 -1 (-7525 3675)(-7525 3725);
WIRE 17 -1 (-7525 3625)(-7525 3675);
WIRE 17 -1 (-7525 3525)(-7525 3550);
WIRE 17 -1 (-7525 3525)(-7525 3475);
WIRE 17 -1 (-7525 3550)(-8025 3550);
FORCEPROP 2 LAST SIG_NAME M_G_CPU1_SB_CB<7:0>
J 0
(-8025 3560);
DISPLAY 0.489362 (-8025 3560);
WIRE 17 -1 (-7525 4675)(-7525 4725);
WIRE 17 -1 (-7525 4725)(-7525 4775);
WIRE 17 -1 (-7525 4775)(-7525 4825);
WIRE 17 -1 (-7525 4825)(-7525 4875);
WIRE 17 -1 (-7525 4875)(-7525 4925);
WIRE 17 -1 (-7525 4925)(-7525 4975);
WIRE 17 -1 (-7525 4975)(-7525 5000);
WIRE 17 -1 (-7525 5000)(-8025 5000);
FORCEPROP 2 LAST SIG_NAME M_G_CPU1_SB_CA<6:0>
J 0
(-8025 5010);
DISPLAY 0.489362 (-8025 5010);
WIRE 17 -1 (-7525 5225)(-7525 5275);
WIRE 17 -1 (-7525 5175)(-7525 5225);
WIRE 17 -1 (-7525 5275)(-7525 5325);
WIRE 17 -1 (-7525 5325)(-7525 5375);
WIRE 17 -1 (-7525 5125)(-7525 5175);
WIRE 17 -1 (-7525 5075)(-7525 5125);
WIRE 17 -1 (-7525 5375)(-7525 5400);
WIRE 17 -1 (-7525 5400)(-8025 5400);
FORCEPROP 2 LAST SIG_NAME M_G_CPU1_SA_CA<6:0>
J 0
(-8025 5410);
DISPLAY 0.489362 (-8025 5410);
WIRE 17 -1 (-7525 3425)(-7525 3475);
WIRE 17 -1 (-7525 3425)(-7525 3375);
WIRE 17 -1 (-7525 3325)(-7525 3375);
WIRE 17 -1 (-7525 3275)(-7525 3325);
WIRE 17 -1 (-7525 3225)(-7525 3275);
WIRE 17 -1 (-7525 3175)(-7525 3225);
WIRE 17 -1 (-5725 5225)(-5725 5175);
WIRE 17 -1 (-5725 5175)(-5725 5125);
WIRE 17 -1 (-5725 5125)(-5725 5075);
WIRE 17 -1 (-5725 5075)(-5725 5025);
WIRE 17 -1 (-5725 5025)(-5725 4975);
WIRE 17 -1 (-5725 4975)(-5725 4925);
WIRE 17 -1 (-5725 4925)(-5725 4875);
WIRE 17 -1 (-5725 4875)(-5725 4825);
WIRE 17 -1 (-5725 4825)(-5725 4775);
WIRE 17 -1 (-5725 4775)(-5725 4725);
WIRE 17 -1 (-5725 4725)(-5725 4675);
WIRE 17 -1 (-5725 4675)(-5725 4625);
WIRE 17 -1 (-5725 4575)(-5725 4625);
WIRE 17 -1 (-5725 4525)(-5725 4575);
WIRE 17 -1 (-5725 4475)(-5725 4525);
WIRE 17 -1 (-5725 4425)(-5725 4475);
WIRE 17 -1 (-5725 4425)(-5725 4375);
WIRE 17 -1 (-5725 4375)(-5725 4325);
WIRE 17 -1 (-5725 4325)(-5725 4275);
WIRE 17 -1 (-5725 4275)(-5725 4225);
WIRE 17 -1 (-5725 4225)(-5725 4175);
WIRE 17 -1 (-5725 4175)(-5725 4125);
WIRE 17 -1 (-5725 4125)(-5725 4075);
WIRE 17 -1 (-5725 4075)(-5725 4025);
WIRE 17 -1 (-5725 3975)(-5725 4025);
WIRE 17 -1 (-5725 3925)(-5725 3975);
WIRE 17 -1 (-5725 3875)(-5725 3925);
WIRE 17 -1 (-5725 3825)(-5725 3875);
WIRE 17 -1 (-5725 3750)(-5725 3725);
WIRE 17 -1 (-5725 3750)(-5225 3750);
FORCEPROP 2 LAST SIG_NAME M_G_CPU1_SB_DQ<31:0>
J 2
(-5225 3760);
DISPLAY 0.489362 (-5225 3760);
WIRE 17 -1 (-5725 3675)(-5725 3625);
WIRE 17 -1 (-5725 3725)(-5725 3675);
WIRE 17 -1 (-5725 3625)(-5725 3575);
WIRE 17 -1 (-5725 3575)(-5725 3525);
WIRE 17 -1 (-5725 3525)(-5725 3475);
WIRE 17 -1 (-5725 3475)(-5725 3425);
WIRE 17 -1 (-5725 3425)(-5725 3375);
WIRE 17 -1 (-5725 3375)(-5725 3325);
WIRE 17 -1 (-5725 3325)(-5725 3275);
WIRE 17 -1 (-5725 3275)(-5725 3225);
WIRE 17 -1 (-5725 3225)(-5725 3175);
WIRE 17 -1 (-5725 3175)(-5725 3125);
WIRE 17 -1 (-5725 3125)(-5725 3075);
WIRE 17 -1 (-5725 3075)(-5725 3025);
WIRE 17 -1 (-5725 3025)(-5725 2975);
WIRE 17 -1 (-5725 2925)(-5725 2975);
WIRE 17 -1 (-5725 2875)(-5725 2925);
WIRE 17 -1 (-5725 2825)(-5725 2875);
WIRE 17 -1 (-5725 2775)(-5725 2825);
WIRE 17 -1 (-5725 2775)(-5725 2725);
WIRE 17 -1 (-5725 2725)(-5725 2675);
WIRE 17 -1 (-5725 2675)(-5725 2625);
WIRE 17 -1 (-5725 2625)(-5725 2575);
WIRE 17 -1 (-5725 2575)(-5725 2525);
WIRE 17 -1 (-5725 2525)(-5725 2475);
WIRE 17 -1 (-5725 2475)(-5725 2425);
WIRE 17 -1 (-5725 2425)(-5725 2375);
WIRE 17 -1 (-5725 2325)(-5725 2375);
WIRE 17 -1 (-5725 2275)(-5725 2325);
WIRE 17 -1 (-5725 2225)(-5725 2275);
WIRE 17 -1 (-5725 2175)(-5725 2225);
WIRE 17 -1 (-3000 4200)(-3000 4100);
WIRE 17 -1 (-3000 4300)(-3000 4200);
WIRE 17 -1 (-3000 4100)(-3000 4000);
WIRE 17 -1 (-3000 3900)(-3000 4000);
WIRE 17 -1 (-3000 4400)(-3000 4300);
WIRE 17 -1 (-3000 4425)(-3000 4400);
WIRE 17 -1 (-3000 3800)(-3000 3900);
WIRE 17 -1 (-3000 3700)(-3000 3800);
WIRE 17 -1 (-3000 4425)(-2500 4425);
FORCEPROP 2 LAST SIG_NAME M_G_CPU1_SA_DQS_DN<9:0>
J 0
(-3035 4435);
DISPLAY 0.489362 (-3035 4435);
WIRE 17 -1 (-3200 4150)(-3200 4050);
WIRE 17 -1 (-3200 4250)(-3200 4150);
WIRE 17 -1 (-3200 3950)(-3200 4050);
WIRE 17 -1 (-3200 3850)(-3200 3950);
WIRE 17 -1 (-3200 4350)(-3200 4250);
WIRE 17 -1 (-3200 4450)(-3200 4350);
WIRE 17 -1 (-3200 3750)(-3200 3850);
WIRE 17 -1 (-3200 3750)(-3200 3650);
WIRE 17 -1 (-3200 4475)(-3200 4450);
WIRE 17 -1 (-3200 4475)(-2500 4475);
FORCEPROP 2 LAST SIG_NAME M_G_CPU1_SA_DQS_DP<9:0>
J 0
(-3035 4485);
DISPLAY 0.489362 (-3035 4485);
WIRE 17 -1 (-3200 3300)(-3200 3200);
WIRE 17 -1 (-3200 3400)(-3200 3300);
WIRE 17 -1 (-3200 3200)(-3200 3100);
WIRE 17 -1 (-3200 3100)(-3200 3000);
WIRE 17 -1 (-3200 3425)(-3200 3400);
WIRE 17 -1 (-3200 3425)(-2500 3425);
FORCEPROP 2 LAST SIG_NAME M_G_CPU1_SB_DQS_DP<9:0>
J 2
(-2500 3435);
DISPLAY 0.489362 (-2500 3435);
WIRE 17 -1 (-3000 3250)(-3000 3150);
WIRE 17 -1 (-3000 3350)(-3000 3250);
WIRE 17 -1 (-3000 3150)(-3000 3050);
WIRE 17 -1 (-3000 3050)(-3000 2950);
WIRE 17 -1 (-3000 3375)(-3000 3350);
WIRE 17 -1 (-3000 3375)(-2500 3375);
FORCEPROP 2 LAST SIG_NAME M_G_CPU1_SB_DQS_DN<9:0>
J 2
(-2500 3385);
DISPLAY 0.489362 (-2500 3385);
WIRE 17 -1 (-3200 2900)(-3200 3000);
WIRE 17 -1 (-3200 2800)(-3200 2900);
WIRE 17 -1 (-3200 2700)(-3200 2800);
WIRE 17 -1 (-3000 3600)(-3000 3500);
WIRE 17 -1 (-3000 3700)(-3000 3600);
WIRE 17 -1 (-3200 3650)(-3200 3550);
WIRE 17 -1 (-3000 2550)(-3000 2450);
WIRE 17 -1 (-3000 2650)(-3000 2550);
WIRE 17 -1 (-3000 2650)(-3000 2750);
WIRE 17 -1 (-3000 2750)(-3000 2850);
WIRE 17 -1 (-3000 2850)(-3000 2950);
WIRE 17 -1 (-3200 2600)(-3200 2500);
WIRE 17 -1 (-3200 2700)(-3200 2600);
WIRE 16 -1 (-6200 950)(-6200 1025);
WIRE 16 -1 (-8675 3025)(-8675 3100);
WIRE 16 -1 (-8525 2350)(-8525 2375);
WIRE 16 -1 (-8275 2350)(-8275 2375);
WIRE 16 -1 (-7625 2625)(-8050 2625);
FORCEPROP 2 LAST SIG_NAME I3C_SPD_DDRGL_CPU1_SCL
J 0
(-8085 2635);
DISPLAY 0.489362 (-8085 2635);
WIRE 16 -1 (-7325 2750)(-7325 2625);
WIRE 16 -1 (-7225 2750)(-7325 2750);
FORCEPROP 2 LAST SIG_NAME I3C_SPD_DDRG_CPU1_SCL
J 0
(-7710 2760);
DISPLAY 0.446809 (-7710 2760);
FORCEPROP 2 LASTPROP $XRERR UNIQUE?
J 0
(-7950 2760);
DISPLAY 0.638298 (-7950 2760);
PAINT MONO (-7950 2760);
DISPLAY INVISIBLE (-7950 2760);
WIRE 16 -1 (-7325 2625)(-7425 2625);
WIRE 16 -1 (-7225 2500)(-8025 2500);
FORCEPROP 2 LAST SIG_NAME PWRGD_CHG_CPU1_DIMM0
J 0
(-7850 2510);
DISPLAY 0.489362 (-7850 2510);
FORCEPROP 2 LASTPROP $XRERR UNIQUE?
J 0
(-8090 2510);
DISPLAY 0.638298 (-8090 2510);
PAINT MONO (-8090 2510);
DISPLAY INVISIBLE (-8090 2510);
WIRE 16 -1 (-8025 2100)(-8025 2500);
WIRE 16 -1 (-8025 2100)(-8275 2100);
WIRE 16 -1 (-8275 2100)(-8300 2100);
WIRE 16 -1 (-8275 2150)(-8275 2100);
WIRE 16 -1 (-7225 2400)(-7850 2400);
FORCEPROP 2 LAST SIG_NAME TP_CHG_CPU1_DIMM0_RFU_6
J 0
(-7850 2410);
DISPLAY 0.489362 (-7850 2410);
FORCEPROP 2 LASTPROP $XRERR UNIQUE?
J 0
(-8090 2400);
DISPLAY 0.638298 (-8090 2400);
PAINT MONO (-8090 2400);
DISPLAY INVISIBLE (-8090 2400);
WIRE 16 -1 (-8675 3300)(-8675 3325);
WIRE 16 -1 (-8675 3325)(-8575 3325);
WIRE 16 -1 (-8575 3375)(-8575 3325);
WIRE 16 -1 (-8575 3325)(-8575 2900);
WIRE 16 -1 (-8575 2900)(-7225 2900);
WIRE 16 -1 (-7225 2350)(-7850 2350);
FORCEPROP 2 LAST SIG_NAME TP_CHG_CPU1_DIMM0_RFU_5
J 0
(-7850 2360);
DISPLAY 0.489362 (-7850 2360);
FORCEPROP 2 LASTPROP $XRERR UNIQUE?
J 0
(-8090 2350);
DISPLAY 0.638298 (-8090 2350);
PAINT MONO (-8090 2350);
DISPLAY INVISIBLE (-8090 2350);
WIRE 16 -1 (-7225 2800)(-8025 2800);
FORCEPROP 2 LAST SIG_NAME I3C_SPD_DDRGL_CPU1_SDA
J 0
(-8035 2810);
DISPLAY 0.489362 (-8035 2810);
WIRE 16 -1 (-7225 2850)(-8025 2850);
FORCEPROP 2 LAST SIG_NAME PD_CHG_CPU1_DIMM0_SAA
J 0
(-8025 2860);
DISPLAY 0.489362 (-8025 2860);
WIRE 16 -1 (-7225 3000)(-8025 3000);
FORCEPROP 2 LAST SIG_NAME M_G_CPU1_ALERT_N
J 0
(-8010 3010);
DISPLAY 0.489362 (-8010 3010);
WIRE 16 -1 (-7225 2300)(-7850 2300);
FORCEPROP 2 LAST SIG_NAME TP_CHG_CPU1_DIMM0_RFU_4
J 0
(-7850 2310);
DISPLAY 0.489362 (-7850 2310);
FORCEPROP 2 LASTPROP $XRERR UNIQUE?
J 0
(-8090 2300);
DISPLAY 0.638298 (-8090 2300);
PAINT MONO (-8090 2300);
DISPLAY INVISIBLE (-8090 2300);
WIRE 16 -1 (-7225 3050)(-8025 3050);
FORCEPROP 2 LAST SIG_NAME M_G_CPU1_RESET_N
J 0
(-8010 3060);
DISPLAY 0.489362 (-8010 3060);
WIRE 16 -1 (-7225 2200)(-7850 2200);
FORCEPROP 2 LAST SIG_NAME TP_CHG_CPU1_DIMM0_RFU_2
J 0
(-7850 2210);
DISPLAY 0.489362 (-7850 2210);
FORCEPROP 2 LASTPROP $XRERR UNIQUE?
J 0
(-8090 2200);
DISPLAY 0.638298 (-8090 2200);
PAINT MONO (-8090 2200);
DISPLAY INVISIBLE (-8090 2200);
WIRE 16 -1 (-7225 5200)(-7425 5200);
WIRE 16 -1 (-7225 5150)(-7425 5150);
WIRE 16 -1 (-7225 5100)(-7425 5100);
WIRE 16 -1 (-7225 5050)(-7425 5050);
WIRE 16 -1 (-1925 5175)(-2125 5175);
WIRE 16 -1 (-2125 5175)(-2125 5225);
WIRE 16 -1 (-1925 5225)(-2125 5225);
WIRE 16 -1 (-2125 5225)(-2125 5275);
WIRE 16 -1 (-1925 5275)(-2125 5275);
WIRE 16 -1 (-2125 5275)(-2125 6075);
WIRE 16 -1 (-2250 6075)(-2125 6075);
WIRE 16 -1 (-2250 6075)(-2825 6075);
WIRE 16 -1 (-2250 6075)(-2250 5975);
WIRE 16 -1 (-2825 6075)(-2825 6150);
WIRE 16 -1 (-2825 5975)(-2825 6075);
WIRE 16 -1 (-525 1975)(-525 1925);
WIRE 16 -1 (-525 2025)(-525 1975);
WIRE 16 -1 (-525 1975)(-725 1975);
WIRE 16 -1 (-525 1925)(-725 1925);
WIRE 16 -1 (-525 1925)(-525 1725);
WIRE 16 -1 (-525 2125)(-525 2025);
WIRE 16 -1 (-525 2025)(-725 2025);
WIRE 16 -1 (-525 2175)(-525 2125);
WIRE 16 -1 (-525 2125)(-725 2125);
WIRE 16 -1 (-525 2225)(-525 2175);
WIRE 16 -1 (-525 2175)(-725 2175);
WIRE 16 -1 (-525 2275)(-525 2225);
WIRE 16 -1 (-525 2225)(-725 2225);
WIRE 16 -1 (-525 2325)(-525 2275);
WIRE 16 -1 (-525 2275)(-725 2275);
WIRE 16 -1 (-525 2375)(-525 2325);
WIRE 16 -1 (-525 2325)(-725 2325);
WIRE 16 -1 (-525 2425)(-525 2375);
WIRE 16 -1 (-525 2375)(-725 2375);
WIRE 16 -1 (-525 2475)(-525 2425);
WIRE 16 -1 (-525 2425)(-725 2425);
WIRE 16 -1 (-525 2525)(-525 2475);
WIRE 16 -1 (-525 2475)(-725 2475);
WIRE 16 -1 (-525 2575)(-525 2525);
WIRE 16 -1 (-525 2525)(-725 2525);
WIRE 16 -1 (-525 2625)(-525 2575);
WIRE 16 -1 (-525 2575)(-725 2575);
WIRE 16 -1 (-525 2675)(-525 2625);
WIRE 16 -1 (-525 2625)(-725 2625);
WIRE 16 -1 (-525 2725)(-525 2675);
WIRE 16 -1 (-525 2675)(-725 2675);
WIRE 16 -1 (-525 2775)(-525 2725);
WIRE 16 -1 (-525 2725)(-725 2725);
WIRE 16 -1 (-525 2825)(-525 2775);
WIRE 16 -1 (-525 2775)(-725 2775);
WIRE 16 -1 (-525 2875)(-525 2825);
WIRE 16 -1 (-525 2825)(-725 2825);
WIRE 16 -1 (-525 2925)(-525 2875);
WIRE 16 -1 (-525 2875)(-725 2875);
WIRE 16 -1 (-525 2975)(-525 2925);
WIRE 16 -1 (-525 2925)(-725 2925);
WIRE 16 -1 (-525 3025)(-525 2975);
WIRE 16 -1 (-525 2975)(-725 2975);
WIRE 16 -1 (-525 3075)(-525 3025);
WIRE 16 -1 (-525 3025)(-725 3025);
WIRE 16 -1 (-525 3125)(-525 3075);
WIRE 16 -1 (-525 3075)(-725 3075);
WIRE 16 -1 (-525 3175)(-525 3125);
WIRE 16 -1 (-525 3125)(-725 3125);
WIRE 16 -1 (-525 3225)(-525 3175);
WIRE 16 -1 (-525 3175)(-725 3175);
WIRE 16 -1 (-525 3275)(-525 3225);
WIRE 16 -1 (-525 3225)(-725 3225);
WIRE 16 -1 (-525 3325)(-525 3275);
WIRE 16 -1 (-525 3275)(-725 3275);
WIRE 16 -1 (-525 3375)(-525 3325);
WIRE 16 -1 (-525 3325)(-725 3325);
WIRE 16 -1 (-525 3425)(-525 3375);
WIRE 16 -1 (-525 3375)(-725 3375);
WIRE 16 -1 (-525 3475)(-525 3425);
WIRE 16 -1 (-525 3425)(-725 3425);
WIRE 16 -1 (-525 3525)(-525 3475);
WIRE 16 -1 (-525 3475)(-725 3475);
WIRE 16 -1 (-525 3575)(-525 3525);
WIRE 16 -1 (-525 3525)(-725 3525);
WIRE 16 -1 (-525 3625)(-525 3575);
WIRE 16 -1 (-525 3575)(-725 3575);
WIRE 16 -1 (-525 3675)(-525 3625);
WIRE 16 -1 (-525 3625)(-725 3625);
WIRE 16 -1 (-525 3725)(-525 3675);
WIRE 16 -1 (-525 3675)(-725 3675);
WIRE 16 -1 (-525 3775)(-525 3725);
WIRE 16 -1 (-525 3725)(-725 3725);
WIRE 16 -1 (-525 3825)(-525 3775);
WIRE 16 -1 (-525 3775)(-725 3775);
WIRE 16 -1 (-525 3875)(-525 3825);
WIRE 16 -1 (-525 3825)(-725 3825);
WIRE 16 -1 (-525 3925)(-525 3875);
WIRE 16 -1 (-525 3875)(-725 3875);
WIRE 16 -1 (-525 3975)(-525 3925);
WIRE 16 -1 (-525 3925)(-725 3925);
WIRE 16 -1 (-525 4025)(-525 3975);
WIRE 16 -1 (-525 3975)(-725 3975);
WIRE 16 -1 (-525 4075)(-525 4025);
WIRE 16 -1 (-525 4025)(-725 4025);
WIRE 16 -1 (-525 4125)(-525 4075);
WIRE 16 -1 (-525 4075)(-725 4075);
WIRE 16 -1 (-525 4175)(-525 4125);
WIRE 16 -1 (-525 4125)(-725 4125);
WIRE 16 -1 (-525 4225)(-525 4175);
WIRE 16 -1 (-525 4175)(-725 4175);
WIRE 16 -1 (-525 4275)(-525 4225);
WIRE 16 -1 (-525 4225)(-725 4225);
WIRE 16 -1 (-525 4325)(-525 4275);
WIRE 16 -1 (-525 4275)(-725 4275);
WIRE 16 -1 (-525 4375)(-525 4325);
WIRE 16 -1 (-525 4325)(-725 4325);
WIRE 16 -1 (-525 4425)(-525 4375);
WIRE 16 -1 (-525 4375)(-725 4375);
WIRE 16 -1 (-525 4475)(-525 4425);
WIRE 16 -1 (-525 4425)(-725 4425);
WIRE 16 -1 (-525 4525)(-525 4475);
WIRE 16 -1 (-525 4475)(-725 4475);
WIRE 16 -1 (-525 4575)(-525 4525);
WIRE 16 -1 (-525 4525)(-725 4525);
WIRE 16 -1 (-525 4625)(-525 4575);
WIRE 16 -1 (-525 4575)(-725 4575);
WIRE 16 -1 (-525 4675)(-525 4625);
WIRE 16 -1 (-525 4625)(-725 4625);
WIRE 16 -1 (-525 4725)(-525 4675);
WIRE 16 -1 (-525 4675)(-725 4675);
WIRE 16 -1 (-525 4775)(-525 4725);
WIRE 16 -1 (-525 4725)(-725 4725);
WIRE 16 -1 (-525 4825)(-525 4775);
WIRE 16 -1 (-525 4775)(-725 4775);
WIRE 16 -1 (-525 4875)(-525 4825);
WIRE 16 -1 (-525 4825)(-725 4825);
WIRE 16 -1 (-525 4925)(-525 4875);
WIRE 16 -1 (-525 4875)(-725 4875);
WIRE 16 -1 (-525 4975)(-525 4925);
WIRE 16 -1 (-525 4925)(-725 4925);
WIRE 16 -1 (-525 5025)(-525 4975);
WIRE 16 -1 (-525 4975)(-725 4975);
WIRE 16 -1 (-525 5075)(-525 5025);
WIRE 16 -1 (-525 5025)(-725 5025);
WIRE 16 -1 (-525 5125)(-525 5075);
WIRE 16 -1 (-525 5075)(-725 5075);
WIRE 16 -1 (-525 5175)(-525 5125);
WIRE 16 -1 (-525 5125)(-725 5125);
WIRE 16 -1 (-525 5225)(-525 5175);
WIRE 16 -1 (-525 5175)(-725 5175);
WIRE 16 -1 (-525 5275)(-525 5225);
WIRE 16 -1 (-525 5225)(-725 5225);
WIRE 16 -1 (-525 5275)(-725 5275);
WIRE 16 -1 (-1925 2025)(-2125 2025);
WIRE 16 -1 (-2125 2075)(-2125 2025);
WIRE 16 -1 (-2125 2025)(-2125 1925);
WIRE 16 -1 (-1925 2075)(-2125 2075);
WIRE 16 -1 (-2125 2125)(-2125 2075);
WIRE 16 -1 (-1925 2125)(-2125 2125);
WIRE 16 -1 (-2125 2175)(-2125 2125);
WIRE 16 -1 (-1925 2175)(-2125 2175);
WIRE 16 -1 (-2125 2225)(-2125 2175);
WIRE 16 -1 (-1925 2225)(-2125 2225);
WIRE 16 -1 (-2125 2275)(-2125 2225);
WIRE 16 -1 (-1925 2275)(-2125 2275);
WIRE 16 -1 (-2125 2325)(-2125 2275);
WIRE 16 -1 (-1925 2325)(-2125 2325);
WIRE 16 -1 (-2125 2375)(-2125 2325);
WIRE 16 -1 (-1925 2375)(-2125 2375);
WIRE 16 -1 (-2125 2425)(-2125 2375);
WIRE 16 -1 (-1925 2425)(-2125 2425);
WIRE 16 -1 (-2125 2475)(-2125 2425);
WIRE 16 -1 (-1925 2475)(-2125 2475);
WIRE 16 -1 (-2125 2525)(-2125 2475);
WIRE 16 -1 (-1925 2525)(-2125 2525);
WIRE 16 -1 (-2125 2575)(-2125 2525);
WIRE 16 -1 (-1925 2575)(-2125 2575);
WIRE 16 -1 (-2125 2625)(-2125 2575);
WIRE 16 -1 (-1925 2625)(-2125 2625);
WIRE 16 -1 (-2125 2675)(-2125 2625);
WIRE 16 -1 (-1925 2675)(-2125 2675);
WIRE 16 -1 (-2125 2725)(-2125 2675);
WIRE 16 -1 (-1925 2725)(-2125 2725);
WIRE 16 -1 (-2125 2775)(-2125 2725);
WIRE 16 -1 (-1925 2775)(-2125 2775);
WIRE 16 -1 (-2125 2825)(-2125 2775);
WIRE 16 -1 (-1925 2825)(-2125 2825);
WIRE 16 -1 (-2125 2875)(-2125 2825);
WIRE 16 -1 (-1925 2875)(-2125 2875);
WIRE 16 -1 (-2125 2925)(-2125 2875);
WIRE 16 -1 (-1925 2925)(-2125 2925);
WIRE 16 -1 (-2125 2975)(-2125 2925);
WIRE 16 -1 (-1925 2975)(-2125 2975);
WIRE 16 -1 (-2125 3025)(-2125 2975);
WIRE 16 -1 (-1925 3025)(-2125 3025);
WIRE 16 -1 (-2125 3075)(-2125 3025);
WIRE 16 -1 (-1925 3075)(-2125 3075);
WIRE 16 -1 (-2125 3125)(-2125 3075);
WIRE 16 -1 (-1925 3125)(-2125 3125);
WIRE 16 -1 (-2125 3175)(-2125 3125);
WIRE 16 -1 (-1925 3175)(-2125 3175);
WIRE 16 -1 (-2125 3225)(-2125 3175);
WIRE 16 -1 (-1925 3225)(-2125 3225);
WIRE 16 -1 (-2125 3275)(-2125 3225);
WIRE 16 -1 (-1925 3275)(-2125 3275);
WIRE 16 -1 (-2125 3325)(-2125 3275);
WIRE 16 -1 (-1925 3325)(-2125 3325);
WIRE 16 -1 (-2125 3375)(-2125 3325);
WIRE 16 -1 (-1925 3375)(-2125 3375);
WIRE 16 -1 (-2125 3425)(-2125 3375);
WIRE 16 -1 (-1925 3425)(-2125 3425);
WIRE 16 -1 (-2125 3475)(-2125 3425);
WIRE 16 -1 (-1925 3475)(-2125 3475);
WIRE 16 -1 (-2125 3525)(-2125 3475);
WIRE 16 -1 (-1925 3525)(-2125 3525);
WIRE 16 -1 (-2125 3575)(-2125 3525);
WIRE 16 -1 (-1925 3575)(-2125 3575);
WIRE 16 -1 (-2125 3625)(-2125 3575);
WIRE 16 -1 (-1925 3625)(-2125 3625);
WIRE 16 -1 (-2125 3675)(-2125 3625);
WIRE 16 -1 (-1925 3675)(-2125 3675);
WIRE 16 -1 (-2125 3725)(-2125 3675);
WIRE 16 -1 (-1925 3725)(-2125 3725);
WIRE 16 -1 (-2125 3775)(-2125 3725);
WIRE 16 -1 (-1925 3775)(-2125 3775);
WIRE 16 -1 (-2125 3825)(-2125 3775);
WIRE 16 -1 (-1925 3825)(-2125 3825);
WIRE 16 -1 (-2125 3875)(-2125 3825);
WIRE 16 -1 (-1925 3875)(-2125 3875);
WIRE 16 -1 (-2125 3925)(-2125 3875);
WIRE 16 -1 (-1925 3925)(-2125 3925);
WIRE 16 -1 (-2125 3975)(-2125 3925);
WIRE 16 -1 (-1925 3975)(-2125 3975);
WIRE 16 -1 (-2125 4025)(-2125 3975);
WIRE 16 -1 (-1925 4025)(-2125 4025);
WIRE 16 -1 (-2125 4075)(-2125 4025);
WIRE 16 -1 (-2125 4125)(-2125 4075);
WIRE 16 -1 (-1925 4075)(-2125 4075);
WIRE 16 -1 (-1925 4125)(-2125 4125);
WIRE 16 -1 (-2125 4175)(-2125 4125);
WIRE 16 -1 (-1925 4175)(-2125 4175);
WIRE 16 -1 (-2125 4225)(-2125 4175);
WIRE 16 -1 (-1925 4225)(-2125 4225);
WIRE 16 -1 (-2125 4275)(-2125 4225);
WIRE 16 -1 (-1925 4275)(-2125 4275);
WIRE 16 -1 (-2125 4325)(-2125 4275);
WIRE 16 -1 (-1925 4325)(-2125 4325);
WIRE 16 -1 (-2125 4375)(-2125 4325);
WIRE 16 -1 (-1925 4375)(-2125 4375);
WIRE 16 -1 (-2125 4425)(-2125 4375);
WIRE 16 -1 (-1925 4425)(-2125 4425);
WIRE 16 -1 (-2125 4475)(-2125 4425);
WIRE 16 -1 (-1925 4475)(-2125 4475);
WIRE 16 -1 (-2125 4525)(-2125 4475);
WIRE 16 -1 (-1925 4525)(-2125 4525);
WIRE 16 -1 (-2125 4575)(-2125 4525);
WIRE 16 -1 (-1925 4575)(-2125 4575);
WIRE 16 -1 (-2125 4625)(-2125 4575);
WIRE 16 -1 (-1925 4625)(-2125 4625);
WIRE 16 -1 (-2125 4675)(-2125 4625);
WIRE 16 -1 (-1925 4675)(-2125 4675);
WIRE 16 -1 (-2125 4725)(-2125 4675);
WIRE 16 -1 (-1925 4725)(-2125 4725);
WIRE 16 -1 (-2125 4775)(-2125 4725);
WIRE 16 -1 (-1925 4775)(-2125 4775);
WIRE 16 -1 (-2125 4825)(-2125 4775);
WIRE 16 -1 (-1925 4825)(-2125 4825);
WIRE 16 -1 (-2125 4875)(-2125 4825);
WIRE 16 -1 (-1925 4875)(-2125 4875);
WIRE 16 -1 (-2125 4925)(-2125 4875);
WIRE 16 -1 (-1925 4925)(-2125 4925);
WIRE 16 -1 (-2125 4975)(-2125 4925);
WIRE 16 -1 (-1925 4975)(-2125 4975);
WIRE 16 -1 (-2125 5025)(-2125 4975);
WIRE 16 -1 (-1925 5025)(-2125 5025);
WIRE 16 -1 (-2125 5075)(-2125 5025);
WIRE 16 -1 (-1925 5075)(-2125 5075);
WIRE 16 -1 (-2125 5125)(-2125 5075);
WIRE 16 -1 (-1925 5125)(-2125 5125);
WIRE 16 -1 (-3500 3375)(-3300 3375);
WIRE 16 -1 (-3500 3325)(-3100 3325);
WIRE 16 -1 (-3500 4425)(-3300 4425);
WIRE 16 -1 (-3500 4375)(-3100 4375);
WIRE 16 -1 (-3300 4325)(-3500 4325);
WIRE 16 -1 (-3500 4275)(-3100 4275);
WIRE 16 -1 (-3500 3125)(-3100 3125);
WIRE 16 -1 (-3300 4225)(-3500 4225);
WIRE 16 -1 (-3300 3075)(-3500 3075);
WIRE 16 -1 (-3500 3025)(-3100 3025);
WIRE 16 -1 (-3500 4075)(-3100 4075);
WIRE 16 -1 (-3500 2975)(-3300 2975);
WIRE 16 -1 (-3500 2925)(-3100 2925);
WIRE 16 -1 (-3500 4025)(-3300 4025);
WIRE 16 -1 (-3500 3975)(-3100 3975);
WIRE 16 -1 (-3300 2875)(-3500 2875);
WIRE 16 -1 (-3500 2825)(-3100 2825);
WIRE 16 -1 (-3300 3925)(-3500 3925);
WIRE 16 -1 (-3500 3875)(-3100 3875);
WIRE 16 -1 (-3300 2775)(-3500 2775);
WIRE 16 -1 (-3500 2725)(-3100 2725);
WIRE 16 -1 (-3300 3825)(-3500 3825);
WIRE 16 -1 (-3500 3775)(-3100 3775);
WIRE 16 -1 (-3300 2675)(-3500 2675);
WIRE 16 -1 (-3500 2625)(-3100 2625);
WIRE 16 -1 (-3300 3725)(-3500 3725);
WIRE 16 -1 (-3500 3675)(-3100 3675);
WIRE 16 -1 (-3500 2575)(-3300 2575);
WIRE 16 -1 (-3500 2525)(-3100 2525);
WIRE 16 -1 (-3500 3625)(-3300 3625);
WIRE 16 -1 (-3500 3575)(-3100 3575);
WIRE 16 -1 (-3300 2475)(-3500 2475);
WIRE 16 -1 (-3500 2425)(-3100 2425);
WIRE 16 -1 (-3300 3525)(-3500 3525);
WIRE 16 -1 (-3500 3475)(-3100 3475);
WIRE 16 -1 (-3300 3175)(-3500 3175);
WIRE 16 -1 (-3500 3225)(-3100 3225);
WIRE 16 -1 (-3300 3275)(-3500 3275);
WIRE 16 -1 (-3300 4125)(-3500 4125);
WIRE 16 -1 (-3500 4175)(-3100 4175);
WIRE 16 -1 (-7225 2100)(-7850 2100);
FORCEPROP 2 LAST SIG_NAME TP_CHG_CPU1_DIMM0_RFU_0
J 0
(-7850 2110);
DISPLAY 0.489362 (-7850 2110);
FORCEPROP 2 LASTPROP $XRERR UNIQUE?
J 0
(-8090 2100);
DISPLAY 0.638298 (-8090 2100);
PAINT MONO (-8090 2100);
DISPLAY INVISIBLE (-8090 2100);
WIRE 16 -1 (-7225 2150)(-7850 2150);
FORCEPROP 2 LAST SIG_NAME TP_CHG_CPU1_DIMM0_RFU_1
J 0
(-7850 2160);
DISPLAY 0.489362 (-7850 2160);
FORCEPROP 2 LASTPROP $XRERR UNIQUE?
J 0
(-8090 2150);
DISPLAY 0.638298 (-8090 2150);
PAINT MONO (-8090 2150);
DISPLAY INVISIBLE (-8090 2150);
WIRE 16 -1 (-7225 2250)(-7850 2250);
FORCEPROP 2 LAST SIG_NAME TP_CHG_CPU1_DIMM0_RFU_3
J 0
(-7850 2260);
DISPLAY 0.489362 (-7850 2260);
FORCEPROP 2 LASTPROP $XRERR UNIQUE?
J 0
(-8090 2250);
DISPLAY 0.638298 (-8090 2250);
PAINT MONO (-8090 2250);
DISPLAY INVISIBLE (-8090 2250);
WIRE 16 -1 (-7225 4500)(-8025 4500);
FORCEPROP 2 LAST SIG_NAME M_G_CPU1_SB_PAR
J 0
(-8025 4510);
DISPLAY 0.489362 (-8025 4510);
WIRE 16 -1 (-7225 4550)(-8025 4550);
FORCEPROP 2 LAST SIG_NAME M_G_CPU1_SA_PAR
J 0
(-8025 4560);
DISPLAY 0.489362 (-8025 4560);
WIRE 16 -1 (-7225 1900)(-8025 1900);
FORCEPROP 2 LAST SIG_NAME M_G_CPU1_SB_RSP<0>
J 0
(-8025 1910);
DISPLAY 0.489362 (-8025 1910);
WIRE 16 -1 (-7225 1950)(-8025 1950);
FORCEPROP 2 LAST SIG_NAME M_G_CPU1_SA_RSP<0>
J 0
(-8025 1960);
DISPLAY 0.489362 (-8025 1960);
WIRE 16 -1 (-5825 2150)(-6025 2150);
WIRE 16 -1 (-5825 2200)(-6025 2200);
WIRE 16 -1 (-5825 2250)(-6025 2250);
WIRE 16 -1 (-6025 2300)(-5825 2300);
WIRE 16 -1 (-5825 2350)(-6025 2350);
WIRE 16 -1 (-5825 2400)(-6025 2400);
WIRE 16 -1 (-5825 2450)(-6025 2450);
WIRE 16 -1 (-6025 2500)(-5825 2500);
WIRE 16 -1 (-5825 2550)(-6025 2550);
WIRE 16 -1 (-5825 2600)(-6025 2600);
WIRE 16 -1 (-5825 2650)(-6025 2650);
WIRE 16 -1 (-6025 2700)(-5825 2700);
WIRE 16 -1 (-5825 2750)(-6025 2750);
WIRE 16 -1 (-5825 2800)(-6025 2800);
WIRE 16 -1 (-5825 2850)(-6025 2850);
WIRE 16 -1 (-6025 2900)(-5825 2900);
WIRE 16 -1 (-5825 2950)(-6025 2950);
WIRE 16 -1 (-5825 3000)(-6025 3000);
WIRE 16 -1 (-5825 3050)(-6025 3050);
WIRE 16 -1 (-6025 3100)(-5825 3100);
WIRE 16 -1 (-5825 3150)(-6025 3150);
WIRE 16 -1 (-5825 3200)(-6025 3200);
WIRE 16 -1 (-5825 3250)(-6025 3250);
WIRE 16 -1 (-6025 3300)(-5825 3300);
WIRE 16 -1 (-5825 3350)(-6025 3350);
WIRE 16 -1 (-5825 3400)(-6025 3400);
WIRE 16 -1 (-5825 3450)(-6025 3450);
WIRE 16 -1 (-6025 3500)(-5825 3500);
WIRE 16 -1 (-5825 3550)(-6025 3550);
WIRE 16 -1 (-5825 3600)(-6025 3600);
WIRE 16 -1 (-5825 3650)(-6025 3650);
WIRE 16 -1 (-6025 3700)(-5825 3700);
WIRE 16 -1 (-5825 3800)(-6025 3800);
WIRE 16 -1 (-5825 3850)(-6025 3850);
WIRE 16 -1 (-5825 3900)(-6025 3900);
WIRE 16 -1 (-6025 3950)(-5825 3950);
WIRE 16 -1 (-5825 4000)(-6025 4000);
WIRE 16 -1 (-5825 4050)(-6025 4050);
WIRE 16 -1 (-5825 4100)(-6025 4100);
WIRE 16 -1 (-6025 4150)(-5825 4150);
WIRE 16 -1 (-5825 4200)(-6025 4200);
WIRE 16 -1 (-5825 4250)(-6025 4250);
WIRE 16 -1 (-5825 4300)(-6025 4300);
WIRE 16 -1 (-6025 4350)(-5825 4350);
WIRE 16 -1 (-5825 4400)(-6025 4400);
WIRE 16 -1 (-5825 4450)(-6025 4450);
WIRE 16 -1 (-5825 4500)(-6025 4500);
WIRE 16 -1 (-6025 4550)(-5825 4550);
WIRE 16 -1 (-5825 4600)(-6025 4600);
WIRE 16 -1 (-5825 4650)(-6025 4650);
WIRE 16 -1 (-5825 4700)(-6025 4700);
WIRE 16 -1 (-6025 4750)(-5825 4750);
WIRE 16 -1 (-5825 4800)(-6025 4800);
WIRE 16 -1 (-5825 4850)(-6025 4850);
WIRE 16 -1 (-5825 4900)(-6025 4900);
WIRE 16 -1 (-6025 4950)(-5825 4950);
WIRE 16 -1 (-5825 5000)(-6025 5000);
WIRE 16 -1 (-5825 5050)(-6025 5050);
WIRE 16 -1 (-5825 5100)(-6025 5100);
WIRE 16 -1 (-6025 5150)(-5825 5150);
WIRE 16 -1 (-5825 5200)(-6025 5200);
WIRE 16 -1 (-5825 5250)(-6025 5250);
WIRE 16 -1 (-5825 5300)(-6025 5300);
WIRE 16 -1 (-7225 4250)(-8025 4250);
FORCEPROP 2 LAST SIG_NAME M_G_CPU1_SB_CS_N<1>
J 0
(-8025 4260);
DISPLAY 0.489362 (-8025 4260);
WIRE 16 -1 (-7225 4400)(-8025 4400);
FORCEPROP 2 LAST SIG_NAME M_G_CPU1_SA_CS_N<1>
J 0
(-8025 4410);
DISPLAY 0.489362 (-8025 4410);
WIRE 16 -1 (-7225 4200)(-8025 4200);
FORCEPROP 2 LAST SIG_NAME M_G_CPU1_SB_CS_N<0>
J 0
(-8025 4210);
DISPLAY 0.489362 (-8025 4210);
WIRE 16 -1 (-7225 4350)(-8025 4350);
FORCEPROP 2 LAST SIG_NAME M_G_CPU1_SA_CS_N<0>
J 0
(-8025 4360);
DISPLAY 0.489362 (-8025 4360);
WIRE 16 -1 (-7225 4100)(-8025 4100);
FORCEPROP 2 LAST SIG_NAME M_G_CPU1_CLK_DP<0>
J 0
(-8025 4110);
DISPLAY 0.489362 (-8025 4110);
WIRE 16 -1 (-7225 4050)(-8025 4050);
FORCEPROP 2 LAST SIG_NAME M_G_CPU1_CLK_DN<0>
J 0
(-8025 4060);
DISPLAY 0.489362 (-8025 4060);
WIRE 16 -1 (-7225 3150)(-7425 3150);
WIRE 16 -1 (-7225 3200)(-7425 3200);
WIRE 16 -1 (-7225 3250)(-7425 3250);
WIRE 16 -1 (-7225 3300)(-7425 3300);
WIRE 16 -1 (-7225 3350)(-7425 3350);
WIRE 16 -1 (-7225 3400)(-7425 3400);
WIRE 16 -1 (-7225 3450)(-7425 3450);
WIRE 16 -1 (-7225 3600)(-7425 3600);
WIRE 16 -1 (-7225 3700)(-7425 3700);
WIRE 16 -1 (-7225 3750)(-7425 3750);
WIRE 16 -1 (-7225 3850)(-7425 3850);
WIRE 16 -1 (-7225 3900)(-7425 3900);
WIRE 16 -1 (-7225 4950)(-7425 4950);
WIRE 16 -1 (-7225 5350)(-7425 5350);
WIRE 16 -1 (-7225 4900)(-7425 4900);
WIRE 16 -1 (-7225 5300)(-7425 5300);
WIRE 16 -1 (-7225 4850)(-7425 4850);
WIRE 16 -1 (-7225 5250)(-7425 5250);
WIRE 16 -1 (-7225 4800)(-7425 4800);
WIRE 16 -1 (-7225 4750)(-7425 4750);
WIRE 16 -1 (-7225 4700)(-7425 4700);
WIRE 16 -1 (-7225 4650)(-7425 4650);
WIRE 16 -1 (-7225 3500)(-7425 3500);
WIRE 16 -1 (-7225 3650)(-7425 3650);
WIRE 16 -1 (-7225 3800)(-7425 3800);
WIRE 16 -1 (-7225 3950)(-7425 3950);
WIRE 16 -1 (-6025 5350)(-5825 5350);
WIRE 16 -1 (-2250 5650)(-2825 5650);
WIRE 16 -1 (-2250 5650)(-2250 5775);
WIRE 16 -1 (-2825 5650)(-2825 5775);
WIRE 16 -1 (-2825 5650)(-2825 5575);
WIRE 16 -1 (-8900 2100)(-8525 2100);
FORCEPROP 2 LAST SIG_NAME PWRGD_CHGL_CPU1
J 0
(-8885 2110);
DISPLAY 0.489362 (-8885 2110);
WIRE 16 -1 (-8525 2100)(-8500 2100);
WIRE 16 -1 (-8525 2150)(-8525 2100);
WIRE 16 -1 (-6200 1300)(-6200 1225);
WIRE 16 -1 (-6200 1300)(-6925 1300);
FORCEPROP 2 LAST SIG_NAME PD_CHG_CPU1_DIMM0_SAA
J 0
(-6910 1310);
DISPLAY 0.489362 (-6910 1310);
DOT 1 (-2250 6075);
DOT 1 (-2825 6075);
DOT 1 (-8525 2100);
DOT 1 (-8275 2100);
DOT 1 (-8575 3325);
DOT 1 (-2125 2025);
DOT 1 (-2125 2125);
DOT 1 (-2125 2075);
DOT 1 (-2125 2175);
DOT 1 (-2125 2225);
DOT 1 (-2125 2275);
DOT 1 (-2125 2375);
DOT 1 (-2125 2325);
DOT 1 (-2125 2425);
DOT 1 (-2125 2475);
DOT 1 (-2125 2525);
DOT 1 (-2125 2575);
DOT 1 (-2125 2675);
DOT 1 (-2125 2625);
DOT 1 (-2125 2725);
DOT 1 (-2125 2775);
DOT 1 (-2125 2825);
DOT 1 (-2125 2925);
DOT 1 (-2125 2875);
DOT 1 (-2125 2975);
DOT 1 (-2125 3025);
DOT 1 (-2125 3075);
DOT 1 (-2125 3125);
DOT 1 (-2125 3175);
DOT 1 (-2125 3225);
DOT 1 (-2125 3275);
DOT 1 (-2125 3325);
DOT 1 (-2125 3375);
DOT 1 (-2125 3425);
DOT 1 (-2125 3475);
DOT 1 (-2125 3525);
DOT 1 (-2125 3575);
DOT 1 (-2125 3625);
DOT 1 (-2125 3675);
DOT 1 (-2125 3725);
DOT 1 (-2125 3775);
DOT 1 (-2125 3825);
DOT 1 (-525 1925);
DOT 1 (-525 1975);
DOT 1 (-525 2025);
DOT 1 (-525 2175);
DOT 1 (-525 2125);
DOT 1 (-525 2225);
DOT 1 (-525 2275);
DOT 1 (-525 2325);
DOT 1 (-525 2375);
DOT 1 (-525 2425);
DOT 1 (-525 2475);
DOT 1 (-525 2525);
DOT 1 (-525 2575);
DOT 1 (-525 2675);
DOT 1 (-525 2625);
DOT 1 (-525 2725);
DOT 1 (-525 2775);
DOT 1 (-525 2825);
DOT 1 (-525 2875);
DOT 1 (-525 2925);
DOT 1 (-525 2975);
DOT 1 (-525 3075);
DOT 1 (-525 3025);
DOT 1 (-525 3125);
DOT 1 (-525 3175);
DOT 1 (-525 3325);
DOT 1 (-525 3225);
DOT 1 (-525 3275);
DOT 1 (-525 3375);
DOT 1 (-525 3425);
DOT 1 (-525 3475);
DOT 1 (-525 3525);
DOT 1 (-525 3575);
DOT 1 (-525 3625);
DOT 1 (-525 3675);
DOT 1 (-525 3725);
DOT 1 (-525 3775);
DOT 1 (-525 3825);
DOT 1 (-2125 3875);
DOT 1 (-2125 3925);
DOT 1 (-2125 3975);
DOT 1 (-2125 4025);
DOT 1 (-2125 4075);
DOT 1 (-2125 4175);
DOT 1 (-2125 4125);
DOT 1 (-2125 4225);
DOT 1 (-2125 4275);
DOT 1 (-2125 4325);
DOT 1 (-2125 4375);
DOT 1 (-2125 4475);
DOT 1 (-2125 4425);
DOT 1 (-2125 4575);
DOT 1 (-2125 4525);
DOT 1 (-2125 4625);
DOT 1 (-2125 4725);
DOT 1 (-2125 4675);
DOT 1 (-2125 4775);
DOT 1 (-2125 4825);
DOT 1 (-2125 4875);
DOT 1 (-2125 4925);
DOT 1 (-2125 4975);
DOT 1 (-2125 5025);
DOT 1 (-2125 5225);
DOT 1 (-2125 5275);
DOT 1 (-525 3925);
DOT 1 (-525 3875);
DOT 1 (-525 3975);
DOT 1 (-525 4025);
DOT 1 (-525 4075);
DOT 1 (-525 4175);
DOT 1 (-525 4125);
DOT 1 (-525 4225);
DOT 1 (-525 4275);
DOT 1 (-525 4325);
DOT 1 (-525 4475);
DOT 1 (-525 4425);
DOT 1 (-525 4375);
DOT 1 (-525 4525);
DOT 1 (-525 4575);
DOT 1 (-525 4625);
DOT 1 (-525 4675);
DOT 1 (-525 4725);
DOT 1 (-525 4775);
DOT 1 (-525 4825);
DOT 1 (-525 4875);
DOT 1 (-525 4925);
DOT 1 (-525 4975);
DOT 1 (-525 5025);
DOT 1 (-525 5125);
DOT 1 (-525 5075);
DOT 1 (-525 5175);
DOT 1 (-525 5225);
DOT 1 (-2125 5075);
DOT 1 (-2825 5650);
QUIT
